FILE_TYPE = MACRO_DRAWING;
SET COLOR_WIRE YELLOW;
SET COLOR_PROP ORANGE;
SET COLOR_DOT WHITE;
SET COLOR_ARC YELLOW;
SET COLOR_BODY GREEN;
SET COLOR_NOTE PURPLE;
SET PROP_DISPLAY VALUE;
SET PAGE_NUMBER P46;
FORCEADD GENOA_SP5..10
(-4525 3525);
FORCEPROP 1 LAST LOCATION U26
J 0
(-5170 6356);
DISPLAY 0.489362 (-5170 6356);
PAINT SKYBLUE (-5170 6356);
FORCEPROP 0 LAST $SEC 10
J 0
(-5150 6400);
DISPLAY 0.680851 (-5150 6400);
PAINT MONO (-5150 6400);
DISPLAY INVISIBLE (-5150 6400);
FORCEPROP 0 LAST CDS_SEC 10
J 0
(-5175 6375);
DISPLAY 1.021277 (-5175 6375);
DISPLAY INVISIBLE (-5175 6375);
FORCEPROP 0 LASTPIN (-5325 2900) $PN BC16
J 2
(-5335 2910);
DISPLAY 0.489362 (-5335 2910);
PAINT MONO (-5335 2910);
FORCEPROP 0 LASTPIN (-5325 2850) $PN BD16
J 2
(-5335 2860);
DISPLAY 0.489362 (-5335 2860);
PAINT MONO (-5335 2860);
FORCEPROP 0 LASTPIN (-5325 1750) $PN BF16
J 2
(-5335 1760);
DISPLAY 0.489362 (-5335 1760);
PAINT MONO (-5335 1760);
FORCEPROP 0 LASTPIN (-5325 1700) $PN BG16
J 2
(-5335 1710);
DISPLAY 0.489362 (-5335 1710);
PAINT MONO (-5335 1710);
FORCEPROP 0 LASTPIN (-5325 2050) $PN AT18
J 2
(-5335 2060);
DISPLAY 0.489362 (-5335 2060);
PAINT MONO (-5335 2060);
FORCEPROP 0 LASTPIN (-5325 1950) $PN AU17
J 2
(-5335 1960);
DISPLAY 0.489362 (-5335 1960);
PAINT MONO (-5335 1960);
FORCEPROP 0 LASTPIN (-5325 2750) $PN AU16
J 2
(-5335 2760);
DISPLAY 0.489362 (-5335 2760);
PAINT MONO (-5335 2760);
FORCEPROP 0 LASTPIN (-5325 2700) $PN AV18
J 2
(-5335 2710);
DISPLAY 0.489362 (-5335 2710);
PAINT MONO (-5335 2710);
FORCEPROP 0 LASTPIN (-5325 2600) $PN BN17
J 2
(-5335 2610);
DISPLAY 0.489362 (-5335 2610);
PAINT MONO (-5335 2610);
FORCEPROP 0 LASTPIN (-5325 1600) $PN AV16
J 2
(-5335 1610);
DISPLAY 0.489362 (-5335 1610);
PAINT MONO (-5335 1610);
FORCEPROP 0 LASTPIN (-5325 1550) $PN AW17
J 2
(-5335 1560);
DISPLAY 0.489362 (-5335 1560);
PAINT MONO (-5335 1560);
FORCEPROP 0 LASTPIN (-5325 1450) $PN BP18
J 2
(-5335 1460);
DISPLAY 0.489362 (-5335 1460);
PAINT MONO (-5335 1460);
FORCEPROP 0 LASTPIN (-5325 3750) $PN AW16
J 2
(-5335 3760);
DISPLAY 0.489362 (-5335 3760);
PAINT MONO (-5335 3760);
FORCEPROP 0 LASTPIN (-5325 3700) $PN AY16
J 2
(-5335 3710);
DISPLAY 0.489362 (-5335 3710);
PAINT MONO (-5335 3710);
FORCEPROP 0 LASTPIN (-5325 3650) $PN AY18
J 2
(-5335 3660);
DISPLAY 0.489362 (-5335 3660);
PAINT MONO (-5335 3660);
FORCEPROP 0 LASTPIN (-5325 3600) $PN BA17
J 2
(-5335 3610);
DISPLAY 0.489362 (-5335 3610);
PAINT MONO (-5335 3610);
FORCEPROP 0 LASTPIN (-5325 3550) $PN BA16
J 2
(-5335 3560);
DISPLAY 0.489362 (-5335 3560);
PAINT MONO (-5335 3560);
FORCEPROP 0 LASTPIN (-5325 3500) $PN BB16
J 2
(-5335 3510);
DISPLAY 0.489362 (-5335 3510);
PAINT MONO (-5335 3510);
FORCEPROP 0 LASTPIN (-5325 3450) $PN BB18
J 2
(-5335 3460);
DISPLAY 0.489362 (-5335 3460);
PAINT MONO (-5335 3460);
FORCEPROP 0 LASTPIN (-3725 2300) $PN AJ16
J 0
(-3715 2310);
DISPLAY 0.489362 (-3715 2310);
PAINT MONO (-3715 2310);
FORCEPROP 0 LASTPIN (-3725 2250) $PN AK18
J 0
(-3715 2260);
DISPLAY 0.489362 (-3715 2260);
PAINT MONO (-3715 2260);
FORCEPROP 0 LASTPIN (-3725 2200) $PN AK16
J 0
(-3715 2210);
DISPLAY 0.489362 (-3715 2210);
PAINT MONO (-3715 2210);
FORCEPROP 0 LASTPIN (-3725 2150) $PN AL17
J 0
(-3715 2160);
DISPLAY 0.489362 (-3715 2160);
PAINT MONO (-3715 2160);
FORCEPROP 0 LASTPIN (-3725 2100) $PN AN16
J 0
(-3715 2110);
DISPLAY 0.489362 (-3715 2110);
PAINT MONO (-3715 2110);
FORCEPROP 0 LASTPIN (-3725 2050) $PN AP18
J 0
(-3715 2060);
DISPLAY 0.489362 (-3715 2060);
PAINT MONO (-3715 2060);
FORCEPROP 0 LASTPIN (-3725 2000) $PN AP16
J 0
(-3715 2010);
DISPLAY 0.489362 (-3715 2010);
PAINT MONO (-3715 2010);
FORCEPROP 0 LASTPIN (-3725 1950) $PN AR17
J 0
(-3715 1960);
DISPLAY 0.489362 (-3715 1960);
PAINT MONO (-3715 1960);
FORCEPROP 0 LASTPIN (-3725 5900) $PN E16
J 0
(-3715 5910);
DISPLAY 0.489362 (-3715 5910);
PAINT MONO (-3715 5910);
FORCEPROP 0 LASTPIN (-3725 5850) $PN F18
J 0
(-3715 5860);
DISPLAY 0.489362 (-3715 5860);
PAINT MONO (-3715 5860);
FORCEPROP 0 LASTPIN (-3725 5800) $PN F16
J 0
(-3715 5810);
DISPLAY 0.489362 (-3715 5810);
PAINT MONO (-3715 5810);
FORCEPROP 0 LASTPIN (-3725 5750) $PN G17
J 0
(-3715 5760);
DISPLAY 0.489362 (-3715 5760);
PAINT MONO (-3715 5760);
FORCEPROP 0 LASTPIN (-3725 5700) $PN J16
J 0
(-3715 5710);
DISPLAY 0.489362 (-3715 5710);
PAINT MONO (-3715 5710);
FORCEPROP 0 LASTPIN (-3725 5650) $PN K18
J 0
(-3715 5660);
DISPLAY 0.489362 (-3715 5660);
PAINT MONO (-3715 5660);
FORCEPROP 0 LASTPIN (-3725 5600) $PN K16
J 0
(-3715 5610);
DISPLAY 0.489362 (-3715 5610);
PAINT MONO (-3715 5610);
FORCEPROP 0 LASTPIN (-3725 5550) $PN L17
J 0
(-3715 5560);
DISPLAY 0.489362 (-3715 5560);
PAINT MONO (-3715 5560);
FORCEPROP 0 LASTPIN (-3725 5450) $PN L16
J 0
(-3715 5460);
DISPLAY 0.489362 (-3715 5460);
PAINT MONO (-3715 5460);
FORCEPROP 0 LASTPIN (-3725 5400) $PN M18
J 0
(-3715 5410);
DISPLAY 0.489362 (-3715 5410);
PAINT MONO (-3715 5410);
FORCEPROP 0 LASTPIN (-3725 5350) $PN M16
J 0
(-3715 5360);
DISPLAY 0.489362 (-3715 5360);
PAINT MONO (-3715 5360);
FORCEPROP 0 LASTPIN (-3725 5300) $PN N17
J 0
(-3715 5310);
DISPLAY 0.489362 (-3715 5310);
PAINT MONO (-3715 5310);
FORCEPROP 0 LASTPIN (-3725 5250) $PN R16
J 0
(-3715 5260);
DISPLAY 0.489362 (-3715 5260);
PAINT MONO (-3715 5260);
FORCEPROP 0 LASTPIN (-3725 5200) $PN T18
J 0
(-3715 5210);
DISPLAY 0.489362 (-3715 5210);
PAINT MONO (-3715 5210);
FORCEPROP 0 LASTPIN (-3725 5150) $PN T16
J 0
(-3715 5160);
DISPLAY 0.489362 (-3715 5160);
PAINT MONO (-3715 5160);
FORCEPROP 0 LASTPIN (-3725 5100) $PN U17
J 0
(-3715 5110);
DISPLAY 0.489362 (-3715 5110);
PAINT MONO (-3715 5110);
FORCEPROP 0 LASTPIN (-3725 5000) $PN U16
J 0
(-3715 5010);
DISPLAY 0.489362 (-3715 5010);
PAINT MONO (-3715 5010);
FORCEPROP 0 LASTPIN (-3725 4950) $PN V18
J 0
(-3715 4960);
DISPLAY 0.489362 (-3715 4960);
PAINT MONO (-3715 4960);
FORCEPROP 0 LASTPIN (-3725 4900) $PN V16
J 0
(-3715 4910);
DISPLAY 0.489362 (-3715 4910);
PAINT MONO (-3715 4910);
FORCEPROP 0 LASTPIN (-3725 4850) $PN W17
J 0
(-3715 4860);
DISPLAY 0.489362 (-3715 4860);
PAINT MONO (-3715 4860);
FORCEPROP 0 LASTPIN (-3725 4800) $PN AA16
J 0
(-3715 4810);
DISPLAY 0.489362 (-3715 4810);
PAINT MONO (-3715 4810);
FORCEPROP 0 LASTPIN (-3725 4750) $PN AB18
J 0
(-3715 4760);
DISPLAY 0.489362 (-3715 4760);
PAINT MONO (-3715 4760);
FORCEPROP 0 LASTPIN (-3725 4700) $PN AB16
J 0
(-3715 4710);
DISPLAY 0.489362 (-3715 4710);
PAINT MONO (-3715 4710);
FORCEPROP 0 LASTPIN (-3725 4650) $PN AC17
J 0
(-3715 4660);
DISPLAY 0.489362 (-3715 4660);
PAINT MONO (-3715 4660);
FORCEPROP 0 LASTPIN (-3725 4550) $PN AC16
J 0
(-3715 4560);
DISPLAY 0.489362 (-3715 4560);
PAINT MONO (-3715 4560);
FORCEPROP 0 LASTPIN (-3725 4500) $PN AD18
J 0
(-3715 4510);
DISPLAY 0.489362 (-3715 4510);
PAINT MONO (-3715 4510);
FORCEPROP 0 LASTPIN (-3725 4450) $PN AD16
J 0
(-3715 4460);
DISPLAY 0.489362 (-3715 4460);
PAINT MONO (-3715 4460);
FORCEPROP 0 LASTPIN (-3725 4400) $PN AE17
J 0
(-3715 4410);
DISPLAY 0.489362 (-3715 4410);
PAINT MONO (-3715 4410);
FORCEPROP 0 LASTPIN (-3725 4350) $PN AG16
J 0
(-3715 4360);
DISPLAY 0.489362 (-3715 4360);
PAINT MONO (-3715 4360);
FORCEPROP 0 LASTPIN (-3725 4300) $PN AH18
J 0
(-3715 4310);
DISPLAY 0.489362 (-3715 4310);
PAINT MONO (-3715 4310);
FORCEPROP 0 LASTPIN (-3725 4250) $PN AH16
J 0
(-3715 4260);
DISPLAY 0.489362 (-3715 4260);
PAINT MONO (-3715 4260);
FORCEPROP 0 LASTPIN (-3725 4200) $PN AJ17
J 0
(-3715 4210);
DISPLAY 0.489362 (-3715 4210);
PAINT MONO (-3715 4210);
FORCEPROP 0 LASTPIN (-5325 5900) $PN G16
J 2
(-5335 5910);
DISPLAY 0.489362 (-5335 5910);
PAINT MONO (-5335 5910);
FORCEPROP 0 LASTPIN (-5325 5800) $PN N16
J 2
(-5335 5810);
DISPLAY 0.489362 (-5335 5810);
PAINT MONO (-5335 5810);
FORCEPROP 0 LASTPIN (-5325 5700) $PN W16
J 2
(-5335 5710);
DISPLAY 0.489362 (-5335 5710);
PAINT MONO (-5335 5710);
FORCEPROP 0 LASTPIN (-5325 5600) $PN AE16
J 2
(-5335 5610);
DISPLAY 0.489362 (-5335 5610);
PAINT MONO (-5335 5610);
FORCEPROP 0 LASTPIN (-5325 5500) $PN AL16
J 2
(-5335 5510);
DISPLAY 0.489362 (-5335 5510);
PAINT MONO (-5335 5510);
FORCEPROP 0 LASTPIN (-5325 5400) $PN J17
J 2
(-5335 5410);
DISPLAY 0.489362 (-5335 5410);
PAINT MONO (-5335 5410);
FORCEPROP 0 LASTPIN (-5325 5300) $PN R17
J 2
(-5335 5310);
DISPLAY 0.489362 (-5335 5310);
PAINT MONO (-5335 5310);
FORCEPROP 0 LASTPIN (-5325 5200) $PN AA17
J 2
(-5335 5210);
DISPLAY 0.489362 (-5335 5210);
PAINT MONO (-5335 5210);
FORCEPROP 0 LASTPIN (-5325 5100) $PN AG17
J 2
(-5335 5110);
DISPLAY 0.489362 (-5335 5110);
PAINT MONO (-5335 5110);
FORCEPROP 0 LASTPIN (-5325 5000) $PN AN17
J 2
(-5335 5010);
DISPLAY 0.489362 (-5335 5010);
PAINT MONO (-5335 5010);
FORCEPROP 0 LASTPIN (-5325 5850) $PN H16
J 2
(-5335 5860);
DISPLAY 0.489362 (-5335 5860);
PAINT MONO (-5335 5860);
FORCEPROP 0 LASTPIN (-5325 5750) $PN P16
J 2
(-5335 5760);
DISPLAY 0.489362 (-5335 5760);
PAINT MONO (-5335 5760);
FORCEPROP 0 LASTPIN (-5325 5650) $PN Y16
J 2
(-5335 5660);
DISPLAY 0.489362 (-5335 5660);
PAINT MONO (-5335 5660);
FORCEPROP 0 LASTPIN (-5325 5550) $PN AF16
J 2
(-5335 5560);
DISPLAY 0.489362 (-5335 5560);
PAINT MONO (-5335 5560);
FORCEPROP 0 LASTPIN (-5325 5450) $PN AM16
J 2
(-5335 5460);
DISPLAY 0.489362 (-5335 5460);
PAINT MONO (-5335 5460);
FORCEPROP 0 LASTPIN (-5325 5350) $PN H18
J 2
(-5335 5360);
DISPLAY 0.489362 (-5335 5360);
PAINT MONO (-5335 5360);
FORCEPROP 0 LASTPIN (-5325 5250) $PN P18
J 2
(-5335 5260);
DISPLAY 0.489362 (-5335 5260);
PAINT MONO (-5335 5260);
FORCEPROP 0 LASTPIN (-5325 5150) $PN Y18
J 2
(-5335 5160);
DISPLAY 0.489362 (-5335 5160);
PAINT MONO (-5335 5160);
FORCEPROP 0 LASTPIN (-5325 5050) $PN AF18
J 2
(-5335 5060);
DISPLAY 0.489362 (-5335 5060);
PAINT MONO (-5335 5060);
FORCEPROP 0 LASTPIN (-5325 4950) $PN AM18
J 2
(-5335 4960);
DISPLAY 0.489362 (-5335 4960);
PAINT MONO (-5335 4960);
FORCEPROP 0 LASTPIN (-5325 2500) $PN BC17
J 2
(-5335 2510);
DISPLAY 0.489362 (-5335 2510);
PAINT MONO (-5335 2510);
FORCEPROP 0 LASTPIN (-5325 2400) $PN BM18
J 2
(-5335 2410);
DISPLAY 0.489362 (-5335 2410);
PAINT MONO (-5335 2410);
FORCEPROP 0 LASTPIN (-5325 2350) $PN BN16
J 2
(-5335 2360);
DISPLAY 0.489362 (-5335 2360);
PAINT MONO (-5335 2360);
FORCEPROP 0 LASTPIN (-5325 2250) $PN BP16
J 2
(-5335 2260);
DISPLAY 0.489362 (-5335 2260);
PAINT MONO (-5335 2260);
FORCEPROP 0 LASTPIN (-5325 1350) $PN BL16
J 2
(-5335 1360);
DISPLAY 0.489362 (-5335 1360);
PAINT MONO (-5335 1360);
FORCEPROP 0 LASTPIN (-5325 1300) $PN BM16
J 2
(-5335 1310);
DISPLAY 0.489362 (-5335 1310);
PAINT MONO (-5335 1310);
FORCEPROP 0 LASTPIN (-5325 1200) $PN BR16
J 2
(-5335 1210);
DISPLAY 0.489362 (-5335 1210);
PAINT MONO (-5335 1210);
FORCEPROP 0 LASTPIN (-5325 3350) $PN BG17
J 2
(-5335 3360);
DISPLAY 0.489362 (-5335 3360);
PAINT MONO (-5335 3360);
FORCEPROP 0 LASTPIN (-5325 3300) $PN BH18
J 2
(-5335 3310);
DISPLAY 0.489362 (-5335 3310);
PAINT MONO (-5335 3310);
FORCEPROP 0 LASTPIN (-5325 3250) $PN BH16
J 2
(-5335 3260);
DISPLAY 0.489362 (-5335 3260);
PAINT MONO (-5335 3260);
FORCEPROP 0 LASTPIN (-5325 3200) $PN BJ16
J 2
(-5335 3210);
DISPLAY 0.489362 (-5335 3210);
PAINT MONO (-5335 3210);
FORCEPROP 0 LASTPIN (-5325 3150) $PN BJ17
J 2
(-5335 3160);
DISPLAY 0.489362 (-5335 3160);
PAINT MONO (-5335 3160);
FORCEPROP 0 LASTPIN (-5325 3100) $PN BK18
J 2
(-5335 3110);
DISPLAY 0.489362 (-5335 3110);
PAINT MONO (-5335 3110);
FORCEPROP 0 LASTPIN (-5325 3050) $PN BK16
J 2
(-5335 3060);
DISPLAY 0.489362 (-5335 3060);
PAINT MONO (-5335 3060);
FORCEPROP 0 LASTPIN (-3725 1850) $PN BY16
J 0
(-3715 1860);
DISPLAY 0.489362 (-3715 1860);
PAINT MONO (-3715 1860);
FORCEPROP 0 LASTPIN (-3725 1800) $PN CA17
J 0
(-3715 1810);
DISPLAY 0.489362 (-3715 1810);
PAINT MONO (-3715 1810);
FORCEPROP 0 LASTPIN (-3725 1750) $PN CA16
J 0
(-3715 1760);
DISPLAY 0.489362 (-3715 1760);
PAINT MONO (-3715 1760);
FORCEPROP 0 LASTPIN (-3725 1700) $PN CB18
J 0
(-3715 1710);
DISPLAY 0.489362 (-3715 1710);
PAINT MONO (-3715 1710);
FORCEPROP 0 LASTPIN (-3725 1650) $PN BT16
J 0
(-3715 1660);
DISPLAY 0.489362 (-3715 1660);
PAINT MONO (-3715 1660);
FORCEPROP 0 LASTPIN (-3725 1600) $PN BU17
J 0
(-3715 1610);
DISPLAY 0.489362 (-3715 1610);
PAINT MONO (-3715 1610);
FORCEPROP 0 LASTPIN (-3725 1550) $PN BU16
J 0
(-3715 1560);
DISPLAY 0.489362 (-3715 1560);
PAINT MONO (-3715 1560);
FORCEPROP 0 LASTPIN (-3725 1500) $PN BV18
J 0
(-3715 1510);
DISPLAY 0.489362 (-3715 1510);
PAINT MONO (-3715 1510);
FORCEPROP 0 LASTPIN (-3725 4100) $PN CB16
J 0
(-3715 4110);
DISPLAY 0.489362 (-3715 4110);
PAINT MONO (-3715 4110);
FORCEPROP 0 LASTPIN (-3725 4050) $PN CC17
J 0
(-3715 4060);
DISPLAY 0.489362 (-3715 4060);
PAINT MONO (-3715 4060);
FORCEPROP 0 LASTPIN (-3725 4000) $PN CC16
J 0
(-3715 4010);
DISPLAY 0.489362 (-3715 4010);
PAINT MONO (-3715 4010);
FORCEPROP 0 LASTPIN (-3725 3950) $PN CD18
J 0
(-3715 3960);
DISPLAY 0.489362 (-3715 3960);
PAINT MONO (-3715 3960);
FORCEPROP 0 LASTPIN (-3725 3900) $PN CF16
J 0
(-3715 3910);
DISPLAY 0.489362 (-3715 3910);
PAINT MONO (-3715 3910);
FORCEPROP 0 LASTPIN (-3725 3850) $PN CG17
J 0
(-3715 3860);
DISPLAY 0.489362 (-3715 3860);
PAINT MONO (-3715 3860);
FORCEPROP 0 LASTPIN (-3725 3800) $PN CG16
J 0
(-3715 3810);
DISPLAY 0.489362 (-3715 3810);
PAINT MONO (-3715 3810);
FORCEPROP 0 LASTPIN (-3725 3750) $PN CH18
J 0
(-3715 3760);
DISPLAY 0.489362 (-3715 3760);
PAINT MONO (-3715 3760);
FORCEPROP 0 LASTPIN (-3725 3650) $PN CH16
J 0
(-3715 3660);
DISPLAY 0.489362 (-3715 3660);
PAINT MONO (-3715 3660);
FORCEPROP 0 LASTPIN (-3725 3600) $PN CJ17
J 0
(-3715 3610);
DISPLAY 0.489362 (-3715 3610);
PAINT MONO (-3715 3610);
FORCEPROP 0 LASTPIN (-3725 3550) $PN CJ16
J 0
(-3715 3560);
DISPLAY 0.489362 (-3715 3560);
PAINT MONO (-3715 3560);
FORCEPROP 0 LASTPIN (-3725 3500) $PN CK18
J 0
(-3715 3510);
DISPLAY 0.489362 (-3715 3510);
PAINT MONO (-3715 3510);
FORCEPROP 0 LASTPIN (-3725 3450) $PN CM16
J 0
(-3715 3460);
DISPLAY 0.489362 (-3715 3460);
PAINT MONO (-3715 3460);
FORCEPROP 0 LASTPIN (-3725 3400) $PN CN17
J 0
(-3715 3410);
DISPLAY 0.489362 (-3715 3410);
PAINT MONO (-3715 3410);
FORCEPROP 0 LASTPIN (-3725 3350) $PN CN16
J 0
(-3715 3360);
DISPLAY 0.489362 (-3715 3360);
PAINT MONO (-3715 3360);
FORCEPROP 0 LASTPIN (-3725 3300) $PN CP18
J 0
(-3715 3310);
DISPLAY 0.489362 (-3715 3310);
PAINT MONO (-3715 3310);
FORCEPROP 0 LASTPIN (-3725 3200) $PN CP16
J 0
(-3715 3210);
DISPLAY 0.489362 (-3715 3210);
PAINT MONO (-3715 3210);
FORCEPROP 0 LASTPIN (-3725 3150) $PN CR17
J 0
(-3715 3160);
DISPLAY 0.489362 (-3715 3160);
PAINT MONO (-3715 3160);
FORCEPROP 0 LASTPIN (-3725 3100) $PN CR16
J 0
(-3715 3110);
DISPLAY 0.489362 (-3715 3110);
PAINT MONO (-3715 3110);
FORCEPROP 0 LASTPIN (-3725 3050) $PN CT18
J 0
(-3715 3060);
DISPLAY 0.489362 (-3715 3060);
PAINT MONO (-3715 3060);
FORCEPROP 0 LASTPIN (-3725 3000) $PN CV16
J 0
(-3715 3010);
DISPLAY 0.489362 (-3715 3010);
PAINT MONO (-3715 3010);
FORCEPROP 0 LASTPIN (-3725 2950) $PN CW17
J 0
(-3715 2960);
DISPLAY 0.489362 (-3715 2960);
PAINT MONO (-3715 2960);
FORCEPROP 0 LASTPIN (-3725 2900) $PN CW16
J 0
(-3715 2910);
DISPLAY 0.489362 (-3715 2910);
PAINT MONO (-3715 2910);
FORCEPROP 0 LASTPIN (-3725 2850) $PN CY18
J 0
(-3715 2860);
DISPLAY 0.489362 (-3715 2860);
PAINT MONO (-3715 2860);
FORCEPROP 0 LASTPIN (-3725 2750) $PN CY16
J 0
(-3715 2760);
DISPLAY 0.489362 (-3715 2760);
PAINT MONO (-3715 2760);
FORCEPROP 0 LASTPIN (-3725 2700) $PN DA17
J 0
(-3715 2710);
DISPLAY 0.489362 (-3715 2710);
PAINT MONO (-3715 2710);
FORCEPROP 0 LASTPIN (-3725 2650) $PN DA16
J 0
(-3715 2660);
DISPLAY 0.489362 (-3715 2660);
PAINT MONO (-3715 2660);
FORCEPROP 0 LASTPIN (-3725 2600) $PN DB18
J 0
(-3715 2610);
DISPLAY 0.489362 (-3715 2610);
PAINT MONO (-3715 2610);
FORCEPROP 0 LASTPIN (-3725 2550) $PN DD16
J 0
(-3715 2560);
DISPLAY 0.489362 (-3715 2560);
PAINT MONO (-3715 2560);
FORCEPROP 0 LASTPIN (-3725 2500) $PN DE17
J 0
(-3715 2510);
DISPLAY 0.489362 (-3715 2510);
PAINT MONO (-3715 2510);
FORCEPROP 0 LASTPIN (-3725 2450) $PN DE16
J 0
(-3715 2460);
DISPLAY 0.489362 (-3715 2460);
PAINT MONO (-3715 2460);
FORCEPROP 0 LASTPIN (-3725 2400) $PN DF16
J 0
(-3715 2410);
DISPLAY 0.489362 (-3715 2410);
PAINT MONO (-3715 2410);
FORCEPROP 0 LASTPIN (-5325 4850) $PN CD16
J 2
(-5335 4860);
DISPLAY 0.489362 (-5335 4860);
PAINT MONO (-5335 4860);
FORCEPROP 0 LASTPIN (-5325 4750) $PN CK16
J 2
(-5335 4760);
DISPLAY 0.489362 (-5335 4760);
PAINT MONO (-5335 4760);
FORCEPROP 0 LASTPIN (-5325 4650) $PN CT16
J 2
(-5335 4660);
DISPLAY 0.489362 (-5335 4660);
PAINT MONO (-5335 4660);
FORCEPROP 0 LASTPIN (-5325 4550) $PN DB16
J 2
(-5335 4560);
DISPLAY 0.489362 (-5335 4560);
PAINT MONO (-5335 4560);
FORCEPROP 0 LASTPIN (-5325 4450) $PN BY18
J 2
(-5335 4460);
DISPLAY 0.489362 (-5335 4460);
PAINT MONO (-5335 4460);
FORCEPROP 0 LASTPIN (-5325 4350) $PN CF18
J 2
(-5335 4360);
DISPLAY 0.489362 (-5335 4360);
PAINT MONO (-5335 4360);
FORCEPROP 0 LASTPIN (-5325 4250) $PN CM18
J 2
(-5335 4260);
DISPLAY 0.489362 (-5335 4260);
PAINT MONO (-5335 4260);
FORCEPROP 0 LASTPIN (-5325 4150) $PN CV18
J 2
(-5335 4160);
DISPLAY 0.489362 (-5335 4160);
PAINT MONO (-5335 4160);
FORCEPROP 0 LASTPIN (-5325 4050) $PN DD18
J 2
(-5335 4060);
DISPLAY 0.489362 (-5335 4060);
PAINT MONO (-5335 4060);
FORCEPROP 0 LASTPIN (-5325 3950) $PN BV16
J 2
(-5335 3960);
DISPLAY 0.489362 (-5335 3960);
PAINT MONO (-5335 3960);
FORCEPROP 0 LASTPIN (-5325 4800) $PN CE16
J 2
(-5335 4810);
DISPLAY 0.489362 (-5335 4810);
PAINT MONO (-5335 4810);
FORCEPROP 0 LASTPIN (-5325 4700) $PN CL16
J 2
(-5335 4710);
DISPLAY 0.489362 (-5335 4710);
PAINT MONO (-5335 4710);
FORCEPROP 0 LASTPIN (-5325 4600) $PN CU16
J 2
(-5335 4610);
DISPLAY 0.489362 (-5335 4610);
PAINT MONO (-5335 4610);
FORCEPROP 0 LASTPIN (-5325 4500) $PN DC16
J 2
(-5335 4510);
DISPLAY 0.489362 (-5335 4510);
PAINT MONO (-5335 4510);
FORCEPROP 0 LASTPIN (-5325 4400) $PN BW17
J 2
(-5335 4410);
DISPLAY 0.489362 (-5335 4410);
PAINT MONO (-5335 4410);
FORCEPROP 0 LASTPIN (-5325 4300) $PN CE17
J 2
(-5335 4310);
DISPLAY 0.489362 (-5335 4310);
PAINT MONO (-5335 4310);
FORCEPROP 0 LASTPIN (-5325 4200) $PN CL17
J 2
(-5335 4210);
DISPLAY 0.489362 (-5335 4210);
PAINT MONO (-5335 4210);
FORCEPROP 0 LASTPIN (-5325 4100) $PN CU17
J 2
(-5335 4110);
DISPLAY 0.489362 (-5335 4110);
PAINT MONO (-5335 4110);
FORCEPROP 0 LASTPIN (-5325 4000) $PN DC17
J 2
(-5335 4010);
DISPLAY 0.489362 (-5335 4010);
PAINT MONO (-5335 4010);
FORCEPROP 0 LASTPIN (-5325 3900) $PN BW16
J 2
(-5335 3910);
DISPLAY 0.489362 (-5335 3910);
PAINT MONO (-5335 3910);
FORCEPROP 0 LASTPIN (-5325 2150) $PN BL17
J 2
(-5335 2160);
DISPLAY 0.489362 (-5335 2160);
PAINT MONO (-5335 2160);
FORCEPROP 0 LASTPIN (-5325 1100) $PN BF18
J 2
(-5335 1110);
DISPLAY 0.489362 (-5335 1110);
PAINT MONO (-5335 1110);
FORCEPROP 2 LAST PART_TYPE SMLF
J 0
(-5175 6305);
DISPLAY 1.021277 (-5175 6305);
FORCEPROP 1 LAST MATERIAL IO
J 0
(-5170 6082);
DISPLAY 0.489362 (-5170 6082);
PAINT SKYBLUE (-5170 6082);
FORCEPROP 2 LAST VALUE SOCKET6096_13568-001
J 0
(-5175 6205);
DISPLAY 0.489362 (-5175 6205);
PAINT SKYBLUE (-5175 6205);
FORCEPROP 1 LAST PART_NUMBER DGA^6000030
J 0
(-5170 6209);
DISPLAY 0.489362 (-5170 6209);
PAINT SKYBLUE (-5170 6209);
FORCEPROP 2 LAST CDS_LIB pure_quanta
J 0
(-4525 3525);
DISPLAY INVISIBLE (-4525 3525);
FORCEPROP 1 LAST CDS_LMAN_SYM_OUTLINE -650,2525,650,-2525
J 0
(-4525 3525);
DISPLAY 0.468085 (-4525 3525);
PAINT GREEN (-4525 3525);
DISPLAY INVISIBLE (-4525 3525);
FORCEPROP 1 LAST NEEDS_NO_SIZE TRUE
J 0
(-4525 3525);
DISPLAY 0.723404 (-4525 3525);
PAINT GREEN (-4525 3525);
DISPLAY INVISIBLE (-4525 3525);
FORCEPROP 1 LAST PATH I159
J 0
(-4525 3525);
DISPLAY 0.723404 (-4525 3525);
PAINT GREEN (-4525 3525);
DISPLAY INVISIBLE (-4525 3525);
FORCEADD OFFPAGE..3
(-2525 5925);
FORCEPROP 2 LAST $XR0 106 
J 0
(-2311 5925);
DISPLAY 0.638298 (-2311 5925);
PAINT MONO (-2311 5925);
FORCEPROP 2 LAST PATH I160
J 0
(-2300 5975);
DISPLAY 1.021277 (-2300 5975);
DISPLAY INVISIBLE (-2300 5975);
FORCEPROP 1 LAST COMMENT_BODY TRUE
J 0
(-2575 5825);
DISPLAY 0.872340 (-2575 5825);
PAINT GREEN (-2575 5825);
DISPLAY INVISIBLE (-2575 5825);
FORCEPROP 1 LAST OFFPAGE TRUE
J 0
(-2200 5800);
DISPLAY 0.872340 (-2200 5800);
PAINT GREEN (-2200 5800);
DISPLAY INVISIBLE (-2200 5800);
FORCEPROP 2 LAST CDS_LIB mstr_standard
J 0
(-2525 5925);
DISPLAY 0.723404 (-2525 5925);
PAINT MONO (-2525 5925);
DISPLAY INVISIBLE (-2525 5925);
FORCEADD TAP..1
(-3250 5900);
FORCEPROP 3 LASTPIN (-3300 5900) SIG_NAME M_J_CPU1_SA_DQ<0>
J 0
(-3290 5910);
DISPLAY 0.659574 (-3290 5910);
PAINT MONO (-3290 5910);
DISPLAY INVISIBLE (-3290 5910);
FORCEPROP 1 LASTPIN (-3300 5900) BN 0
J 0
(-3312 5908);
DISPLAY 0.489362 (-3312 5908);
PAINT GREEN (-3312 5908);
FORCEPROP 2 LAST CDS_LIB mstr_standard
J 0
(-3250 5900);
DISPLAY 0.723404 (-3250 5900);
PAINT MONO (-3250 5900);
DISPLAY INVISIBLE (-3250 5900);
FORCEPROP 1 LAST BODY_TYPE PLUMBING
J 0
(-3250 5950);
DISPLAY 0.872340 (-3250 5950);
PAINT GREEN (-3250 5950);
DISPLAY INVISIBLE (-3250 5950);
FORCEPROP 1 LAST HDL_TAP TRUE
J 0
(-2925 5775);
DISPLAY 0.872340 (-2925 5775);
DISPLAY INVISIBLE (-2925 5775);
FORCEPROP 1 LAST PATH I161
J 0
(-3252 5900);
DISPLAY 0.872340 (-3252 5900);
PAINT GREEN (-3252 5900);
DISPLAY INVISIBLE (-3252 5900);
FORCEADD TAP..1
(-3250 5850);
FORCEPROP 3 LASTPIN (-3300 5850) SIG_NAME M_J_CPU1_SA_DQ<1>
J 0
(-3290 5860);
DISPLAY 0.659574 (-3290 5860);
PAINT MONO (-3290 5860);
DISPLAY INVISIBLE (-3290 5860);
FORCEPROP 1 LASTPIN (-3300 5850) BN 1
J 0
(-3312 5858);
DISPLAY 0.489362 (-3312 5858);
PAINT GREEN (-3312 5858);
FORCEPROP 2 LAST CDS_LIB mstr_standard
J 0
(-3250 5850);
DISPLAY 0.723404 (-3250 5850);
PAINT MONO (-3250 5850);
DISPLAY INVISIBLE (-3250 5850);
FORCEPROP 1 LAST BODY_TYPE PLUMBING
J 0
(-3250 5900);
DISPLAY 0.872340 (-3250 5900);
PAINT GREEN (-3250 5900);
DISPLAY INVISIBLE (-3250 5900);
FORCEPROP 1 LAST HDL_TAP TRUE
J 0
(-2925 5725);
DISPLAY 0.872340 (-2925 5725);
DISPLAY INVISIBLE (-2925 5725);
FORCEPROP 1 LAST PATH I162
J 0
(-3252 5850);
DISPLAY 0.872340 (-3252 5850);
PAINT GREEN (-3252 5850);
DISPLAY INVISIBLE (-3252 5850);
FORCEADD TAP..1
(-3250 5800);
FORCEPROP 3 LASTPIN (-3300 5800) SIG_NAME M_J_CPU1_SA_DQ<2>
J 0
(-3290 5810);
DISPLAY 0.659574 (-3290 5810);
PAINT MONO (-3290 5810);
DISPLAY INVISIBLE (-3290 5810);
FORCEPROP 1 LASTPIN (-3300 5800) BN 2
J 0
(-3312 5808);
DISPLAY 0.489362 (-3312 5808);
PAINT GREEN (-3312 5808);
FORCEPROP 2 LAST CDS_LIB mstr_standard
J 0
(-3250 5800);
DISPLAY 0.723404 (-3250 5800);
PAINT MONO (-3250 5800);
DISPLAY INVISIBLE (-3250 5800);
FORCEPROP 1 LAST BODY_TYPE PLUMBING
J 0
(-3250 5850);
DISPLAY 0.872340 (-3250 5850);
PAINT GREEN (-3250 5850);
DISPLAY INVISIBLE (-3250 5850);
FORCEPROP 1 LAST HDL_TAP TRUE
J 0
(-2925 5675);
DISPLAY 0.872340 (-2925 5675);
DISPLAY INVISIBLE (-2925 5675);
FORCEPROP 1 LAST PATH I163
J 0
(-3252 5800);
DISPLAY 0.872340 (-3252 5800);
PAINT GREEN (-3252 5800);
DISPLAY INVISIBLE (-3252 5800);
FORCEADD TAP..1
(-3250 5700);
FORCEPROP 3 LASTPIN (-3300 5700) SIG_NAME M_J_CPU1_SA_DQ<4>
J 0
(-3290 5710);
DISPLAY 0.659574 (-3290 5710);
PAINT MONO (-3290 5710);
DISPLAY INVISIBLE (-3290 5710);
FORCEPROP 1 LASTPIN (-3300 5700) BN 4
J 0
(-3312 5708);
DISPLAY 0.489362 (-3312 5708);
PAINT GREEN (-3312 5708);
FORCEPROP 2 LAST CDS_LIB mstr_standard
J 0
(-3250 5700);
DISPLAY 0.723404 (-3250 5700);
PAINT MONO (-3250 5700);
DISPLAY INVISIBLE (-3250 5700);
FORCEPROP 1 LAST BODY_TYPE PLUMBING
J 0
(-3250 5750);
DISPLAY 0.872340 (-3250 5750);
PAINT GREEN (-3250 5750);
DISPLAY INVISIBLE (-3250 5750);
FORCEPROP 1 LAST HDL_TAP TRUE
J 0
(-2925 5575);
DISPLAY 0.872340 (-2925 5575);
DISPLAY INVISIBLE (-2925 5575);
FORCEPROP 1 LAST PATH I164
J 0
(-3252 5700);
DISPLAY 0.872340 (-3252 5700);
PAINT GREEN (-3252 5700);
DISPLAY INVISIBLE (-3252 5700);
FORCEADD TAP..1
(-3250 5750);
FORCEPROP 3 LASTPIN (-3300 5750) SIG_NAME M_J_CPU1_SA_DQ<3>
J 0
(-3290 5760);
DISPLAY 0.659574 (-3290 5760);
PAINT MONO (-3290 5760);
DISPLAY INVISIBLE (-3290 5760);
FORCEPROP 1 LASTPIN (-3300 5750) BN 3
J 0
(-3312 5758);
DISPLAY 0.489362 (-3312 5758);
PAINT GREEN (-3312 5758);
FORCEPROP 2 LAST CDS_LIB mstr_standard
J 0
(-3250 5750);
DISPLAY 0.723404 (-3250 5750);
PAINT MONO (-3250 5750);
DISPLAY INVISIBLE (-3250 5750);
FORCEPROP 1 LAST BODY_TYPE PLUMBING
J 0
(-3250 5800);
DISPLAY 0.872340 (-3250 5800);
PAINT GREEN (-3250 5800);
DISPLAY INVISIBLE (-3250 5800);
FORCEPROP 1 LAST HDL_TAP TRUE
J 0
(-2925 5625);
DISPLAY 0.872340 (-2925 5625);
DISPLAY INVISIBLE (-2925 5625);
FORCEPROP 1 LAST PATH I165
J 0
(-3252 5750);
DISPLAY 0.872340 (-3252 5750);
PAINT GREEN (-3252 5750);
DISPLAY INVISIBLE (-3252 5750);
FORCEADD TAP..1
(-3250 5650);
FORCEPROP 3 LASTPIN (-3300 5650) SIG_NAME M_J_CPU1_SA_DQ<5>
J 0
(-3290 5660);
DISPLAY 0.659574 (-3290 5660);
PAINT MONO (-3290 5660);
DISPLAY INVISIBLE (-3290 5660);
FORCEPROP 1 LASTPIN (-3300 5650) BN 5
J 0
(-3312 5658);
DISPLAY 0.489362 (-3312 5658);
PAINT GREEN (-3312 5658);
FORCEPROP 2 LAST CDS_LIB mstr_standard
J 0
(-3250 5650);
DISPLAY 0.723404 (-3250 5650);
PAINT MONO (-3250 5650);
DISPLAY INVISIBLE (-3250 5650);
FORCEPROP 1 LAST BODY_TYPE PLUMBING
J 0
(-3250 5700);
DISPLAY 0.872340 (-3250 5700);
PAINT GREEN (-3250 5700);
DISPLAY INVISIBLE (-3250 5700);
FORCEPROP 1 LAST HDL_TAP TRUE
J 0
(-2925 5525);
DISPLAY 0.872340 (-2925 5525);
DISPLAY INVISIBLE (-2925 5525);
FORCEPROP 1 LAST PATH I166
J 0
(-3252 5650);
DISPLAY 0.872340 (-3252 5650);
PAINT GREEN (-3252 5650);
DISPLAY INVISIBLE (-3252 5650);
FORCEADD TAP..1
(-3250 5600);
FORCEPROP 3 LASTPIN (-3300 5600) SIG_NAME M_J_CPU1_SA_DQ<6>
J 0
(-3290 5610);
DISPLAY 0.659574 (-3290 5610);
PAINT MONO (-3290 5610);
DISPLAY INVISIBLE (-3290 5610);
FORCEPROP 1 LASTPIN (-3300 5600) BN 6
J 0
(-3312 5608);
DISPLAY 0.489362 (-3312 5608);
PAINT GREEN (-3312 5608);
FORCEPROP 2 LAST CDS_LIB mstr_standard
J 0
(-3250 5600);
DISPLAY 0.723404 (-3250 5600);
PAINT MONO (-3250 5600);
DISPLAY INVISIBLE (-3250 5600);
FORCEPROP 1 LAST BODY_TYPE PLUMBING
J 0
(-3250 5650);
DISPLAY 0.872340 (-3250 5650);
PAINT GREEN (-3250 5650);
DISPLAY INVISIBLE (-3250 5650);
FORCEPROP 1 LAST HDL_TAP TRUE
J 0
(-2925 5475);
DISPLAY 0.872340 (-2925 5475);
DISPLAY INVISIBLE (-2925 5475);
FORCEPROP 1 LAST PATH I167
J 0
(-3252 5600);
DISPLAY 0.872340 (-3252 5600);
PAINT GREEN (-3252 5600);
DISPLAY INVISIBLE (-3252 5600);
FORCEADD TAP..1
(-3250 5550);
FORCEPROP 3 LASTPIN (-3300 5550) SIG_NAME M_J_CPU1_SA_DQ<7>
J 0
(-3290 5560);
DISPLAY 0.659574 (-3290 5560);
PAINT MONO (-3290 5560);
DISPLAY INVISIBLE (-3290 5560);
FORCEPROP 1 LASTPIN (-3300 5550) BN 7
J 0
(-3312 5558);
DISPLAY 0.489362 (-3312 5558);
PAINT GREEN (-3312 5558);
FORCEPROP 2 LAST CDS_LIB mstr_standard
J 0
(-3250 5550);
DISPLAY 0.723404 (-3250 5550);
PAINT MONO (-3250 5550);
DISPLAY INVISIBLE (-3250 5550);
FORCEPROP 1 LAST BODY_TYPE PLUMBING
J 0
(-3250 5600);
DISPLAY 0.872340 (-3250 5600);
PAINT GREEN (-3250 5600);
DISPLAY INVISIBLE (-3250 5600);
FORCEPROP 1 LAST HDL_TAP TRUE
J 0
(-2925 5425);
DISPLAY 0.872340 (-2925 5425);
DISPLAY INVISIBLE (-2925 5425);
FORCEPROP 1 LAST PATH I168
J 0
(-3252 5550);
DISPLAY 0.872340 (-3252 5550);
PAINT GREEN (-3252 5550);
DISPLAY INVISIBLE (-3252 5550);
FORCEADD TAP..1
(-3250 5400);
FORCEPROP 3 LASTPIN (-3300 5400) SIG_NAME M_J_CPU1_SA_DQ<9>
J 0
(-3290 5410);
DISPLAY 0.659574 (-3290 5410);
PAINT MONO (-3290 5410);
DISPLAY INVISIBLE (-3290 5410);
FORCEPROP 1 LASTPIN (-3300 5400) BN 9
J 0
(-3312 5408);
DISPLAY 0.489362 (-3312 5408);
PAINT GREEN (-3312 5408);
FORCEPROP 2 LAST CDS_LIB mstr_standard
J 0
(-3250 5400);
DISPLAY 0.723404 (-3250 5400);
PAINT MONO (-3250 5400);
DISPLAY INVISIBLE (-3250 5400);
FORCEPROP 1 LAST BODY_TYPE PLUMBING
J 0
(-3250 5450);
DISPLAY 0.872340 (-3250 5450);
PAINT GREEN (-3250 5450);
DISPLAY INVISIBLE (-3250 5450);
FORCEPROP 1 LAST HDL_TAP TRUE
J 0
(-2925 5275);
DISPLAY 0.872340 (-2925 5275);
DISPLAY INVISIBLE (-2925 5275);
FORCEPROP 1 LAST PATH I169
J 0
(-3252 5400);
DISPLAY 0.872340 (-3252 5400);
PAINT GREEN (-3252 5400);
DISPLAY INVISIBLE (-3252 5400);
FORCEADD TAP..1
(-3250 5450);
FORCEPROP 3 LASTPIN (-3300 5450) SIG_NAME M_J_CPU1_SA_DQ<8>
J 0
(-3290 5460);
DISPLAY 0.659574 (-3290 5460);
PAINT MONO (-3290 5460);
DISPLAY INVISIBLE (-3290 5460);
FORCEPROP 1 LASTPIN (-3300 5450) BN 8
J 0
(-3312 5458);
DISPLAY 0.489362 (-3312 5458);
PAINT GREEN (-3312 5458);
FORCEPROP 2 LAST CDS_LIB mstr_standard
J 0
(-3250 5450);
DISPLAY 0.723404 (-3250 5450);
PAINT MONO (-3250 5450);
DISPLAY INVISIBLE (-3250 5450);
FORCEPROP 1 LAST BODY_TYPE PLUMBING
J 0
(-3250 5500);
DISPLAY 0.872340 (-3250 5500);
PAINT GREEN (-3250 5500);
DISPLAY INVISIBLE (-3250 5500);
FORCEPROP 1 LAST HDL_TAP TRUE
J 0
(-2925 5325);
DISPLAY 0.872340 (-2925 5325);
DISPLAY INVISIBLE (-2925 5325);
FORCEPROP 1 LAST PATH I170
J 0
(-3252 5450);
DISPLAY 0.872340 (-3252 5450);
PAINT GREEN (-3252 5450);
DISPLAY INVISIBLE (-3252 5450);
FORCEADD TAP..1
(-3250 5350);
FORCEPROP 3 LASTPIN (-3300 5350) SIG_NAME M_J_CPU1_SA_DQ<10>
J 0
(-3290 5360);
DISPLAY 0.659574 (-3290 5360);
PAINT MONO (-3290 5360);
DISPLAY INVISIBLE (-3290 5360);
FORCEPROP 1 LASTPIN (-3300 5350) BN 10
J 0
(-3312 5358);
DISPLAY 0.489362 (-3312 5358);
PAINT GREEN (-3312 5358);
FORCEPROP 2 LAST CDS_LIB mstr_standard
J 0
(-3250 5350);
DISPLAY 0.723404 (-3250 5350);
PAINT MONO (-3250 5350);
DISPLAY INVISIBLE (-3250 5350);
FORCEPROP 1 LAST BODY_TYPE PLUMBING
J 0
(-3250 5400);
DISPLAY 0.872340 (-3250 5400);
PAINT GREEN (-3250 5400);
DISPLAY INVISIBLE (-3250 5400);
FORCEPROP 1 LAST HDL_TAP TRUE
J 0
(-2925 5225);
DISPLAY 0.872340 (-2925 5225);
DISPLAY INVISIBLE (-2925 5225);
FORCEPROP 1 LAST PATH I171
J 0
(-3252 5350);
DISPLAY 0.872340 (-3252 5350);
PAINT GREEN (-3252 5350);
DISPLAY INVISIBLE (-3252 5350);
FORCEADD TAP..1
(-3250 5300);
FORCEPROP 3 LASTPIN (-3300 5300) SIG_NAME M_J_CPU1_SA_DQ<11>
J 0
(-3290 5310);
DISPLAY 0.659574 (-3290 5310);
PAINT MONO (-3290 5310);
DISPLAY INVISIBLE (-3290 5310);
FORCEPROP 1 LASTPIN (-3300 5300) BN 11
J 0
(-3312 5308);
DISPLAY 0.489362 (-3312 5308);
PAINT GREEN (-3312 5308);
FORCEPROP 2 LAST CDS_LIB mstr_standard
J 0
(-3250 5300);
DISPLAY 0.723404 (-3250 5300);
PAINT MONO (-3250 5300);
DISPLAY INVISIBLE (-3250 5300);
FORCEPROP 1 LAST BODY_TYPE PLUMBING
J 0
(-3250 5350);
DISPLAY 0.872340 (-3250 5350);
PAINT GREEN (-3250 5350);
DISPLAY INVISIBLE (-3250 5350);
FORCEPROP 1 LAST HDL_TAP TRUE
J 0
(-2925 5175);
DISPLAY 0.872340 (-2925 5175);
DISPLAY INVISIBLE (-2925 5175);
FORCEPROP 1 LAST PATH I172
J 0
(-3252 5300);
DISPLAY 0.872340 (-3252 5300);
PAINT GREEN (-3252 5300);
DISPLAY INVISIBLE (-3252 5300);
FORCEADD TAP..1
(-3250 5250);
FORCEPROP 3 LASTPIN (-3300 5250) SIG_NAME M_J_CPU1_SA_DQ<12>
J 0
(-3290 5260);
DISPLAY 0.659574 (-3290 5260);
PAINT MONO (-3290 5260);
DISPLAY INVISIBLE (-3290 5260);
FORCEPROP 1 LASTPIN (-3300 5250) BN 12
J 0
(-3312 5258);
DISPLAY 0.489362 (-3312 5258);
PAINT GREEN (-3312 5258);
FORCEPROP 2 LAST CDS_LIB mstr_standard
J 0
(-3250 5250);
DISPLAY 0.723404 (-3250 5250);
PAINT MONO (-3250 5250);
DISPLAY INVISIBLE (-3250 5250);
FORCEPROP 1 LAST BODY_TYPE PLUMBING
J 0
(-3250 5300);
DISPLAY 0.872340 (-3250 5300);
PAINT GREEN (-3250 5300);
DISPLAY INVISIBLE (-3250 5300);
FORCEPROP 1 LAST HDL_TAP TRUE
J 0
(-2925 5125);
DISPLAY 0.872340 (-2925 5125);
DISPLAY INVISIBLE (-2925 5125);
FORCEPROP 1 LAST PATH I173
J 0
(-3252 5250);
DISPLAY 0.872340 (-3252 5250);
PAINT GREEN (-3252 5250);
DISPLAY INVISIBLE (-3252 5250);
FORCEADD TAP..1
(-3250 5200);
FORCEPROP 3 LASTPIN (-3300 5200) SIG_NAME M_J_CPU1_SA_DQ<13>
J 0
(-3290 5210);
DISPLAY 0.659574 (-3290 5210);
PAINT MONO (-3290 5210);
DISPLAY INVISIBLE (-3290 5210);
FORCEPROP 1 LASTPIN (-3300 5200) BN 13
J 0
(-3312 5208);
DISPLAY 0.489362 (-3312 5208);
PAINT GREEN (-3312 5208);
FORCEPROP 2 LAST CDS_LIB mstr_standard
J 0
(-3250 5200);
DISPLAY 0.723404 (-3250 5200);
PAINT MONO (-3250 5200);
DISPLAY INVISIBLE (-3250 5200);
FORCEPROP 1 LAST BODY_TYPE PLUMBING
J 0
(-3250 5250);
DISPLAY 0.872340 (-3250 5250);
PAINT GREEN (-3250 5250);
DISPLAY INVISIBLE (-3250 5250);
FORCEPROP 1 LAST HDL_TAP TRUE
J 0
(-2925 5075);
DISPLAY 0.872340 (-2925 5075);
DISPLAY INVISIBLE (-2925 5075);
FORCEPROP 1 LAST PATH I174
J 0
(-3252 5200);
DISPLAY 0.872340 (-3252 5200);
PAINT GREEN (-3252 5200);
DISPLAY INVISIBLE (-3252 5200);
FORCEADD TAP..1
(-3250 5150);
FORCEPROP 3 LASTPIN (-3300 5150) SIG_NAME M_J_CPU1_SA_DQ<14>
J 0
(-3290 5160);
DISPLAY 0.659574 (-3290 5160);
PAINT MONO (-3290 5160);
DISPLAY INVISIBLE (-3290 5160);
FORCEPROP 1 LASTPIN (-3300 5150) BN 14
J 0
(-3312 5158);
DISPLAY 0.489362 (-3312 5158);
PAINT GREEN (-3312 5158);
FORCEPROP 2 LAST CDS_LIB mstr_standard
J 0
(-3250 5150);
DISPLAY 0.723404 (-3250 5150);
PAINT MONO (-3250 5150);
DISPLAY INVISIBLE (-3250 5150);
FORCEPROP 1 LAST BODY_TYPE PLUMBING
J 0
(-3250 5200);
DISPLAY 0.872340 (-3250 5200);
PAINT GREEN (-3250 5200);
DISPLAY INVISIBLE (-3250 5200);
FORCEPROP 1 LAST HDL_TAP TRUE
J 0
(-2925 5025);
DISPLAY 0.872340 (-2925 5025);
DISPLAY INVISIBLE (-2925 5025);
FORCEPROP 1 LAST PATH I175
J 0
(-3252 5150);
DISPLAY 0.872340 (-3252 5150);
PAINT GREEN (-3252 5150);
DISPLAY INVISIBLE (-3252 5150);
FORCEADD TAP..1
(-3250 5100);
FORCEPROP 3 LASTPIN (-3300 5100) SIG_NAME M_J_CPU1_SA_DQ<15>
J 0
(-3290 5110);
DISPLAY 0.659574 (-3290 5110);
PAINT MONO (-3290 5110);
DISPLAY INVISIBLE (-3290 5110);
FORCEPROP 1 LASTPIN (-3300 5100) BN 15
J 0
(-3312 5108);
DISPLAY 0.489362 (-3312 5108);
PAINT GREEN (-3312 5108);
FORCEPROP 2 LAST CDS_LIB mstr_standard
J 0
(-3250 5100);
DISPLAY 0.723404 (-3250 5100);
PAINT MONO (-3250 5100);
DISPLAY INVISIBLE (-3250 5100);
FORCEPROP 1 LAST BODY_TYPE PLUMBING
J 0
(-3250 5150);
DISPLAY 0.872340 (-3250 5150);
PAINT GREEN (-3250 5150);
DISPLAY INVISIBLE (-3250 5150);
FORCEPROP 1 LAST HDL_TAP TRUE
J 0
(-2925 4975);
DISPLAY 0.872340 (-2925 4975);
DISPLAY INVISIBLE (-2925 4975);
FORCEPROP 1 LAST PATH I176
J 0
(-3252 5100);
DISPLAY 0.872340 (-3252 5100);
PAINT GREEN (-3252 5100);
DISPLAY INVISIBLE (-3252 5100);
FORCEADD TAP..1
(-3250 5000);
FORCEPROP 3 LASTPIN (-3300 5000) SIG_NAME M_J_CPU1_SA_DQ<16>
J 0
(-3290 5010);
DISPLAY 0.659574 (-3290 5010);
PAINT MONO (-3290 5010);
DISPLAY INVISIBLE (-3290 5010);
FORCEPROP 1 LASTPIN (-3300 5000) BN 16
J 0
(-3312 5008);
DISPLAY 0.489362 (-3312 5008);
PAINT GREEN (-3312 5008);
FORCEPROP 2 LAST CDS_LIB mstr_standard
J 0
(-3250 5000);
DISPLAY 0.723404 (-3250 5000);
PAINT MONO (-3250 5000);
DISPLAY INVISIBLE (-3250 5000);
FORCEPROP 1 LAST BODY_TYPE PLUMBING
J 0
(-3250 5050);
DISPLAY 0.872340 (-3250 5050);
PAINT GREEN (-3250 5050);
DISPLAY INVISIBLE (-3250 5050);
FORCEPROP 1 LAST HDL_TAP TRUE
J 0
(-2925 4875);
DISPLAY 0.872340 (-2925 4875);
DISPLAY INVISIBLE (-2925 4875);
FORCEPROP 1 LAST PATH I177
J 0
(-3252 5000);
DISPLAY 0.872340 (-3252 5000);
PAINT GREEN (-3252 5000);
DISPLAY INVISIBLE (-3252 5000);
FORCEADD TAP..1
(-3250 4950);
FORCEPROP 3 LASTPIN (-3300 4950) SIG_NAME M_J_CPU1_SA_DQ<17>
J 0
(-3290 4960);
DISPLAY 0.659574 (-3290 4960);
PAINT MONO (-3290 4960);
DISPLAY INVISIBLE (-3290 4960);
FORCEPROP 1 LASTPIN (-3300 4950) BN 17
J 0
(-3312 4958);
DISPLAY 0.489362 (-3312 4958);
PAINT GREEN (-3312 4958);
FORCEPROP 2 LAST CDS_LIB mstr_standard
J 0
(-3250 4950);
DISPLAY 0.723404 (-3250 4950);
PAINT MONO (-3250 4950);
DISPLAY INVISIBLE (-3250 4950);
FORCEPROP 1 LAST BODY_TYPE PLUMBING
J 0
(-3250 5000);
DISPLAY 0.872340 (-3250 5000);
PAINT GREEN (-3250 5000);
DISPLAY INVISIBLE (-3250 5000);
FORCEPROP 1 LAST HDL_TAP TRUE
J 0
(-2925 4825);
DISPLAY 0.872340 (-2925 4825);
DISPLAY INVISIBLE (-2925 4825);
FORCEPROP 1 LAST PATH I178
J 0
(-3252 4950);
DISPLAY 0.872340 (-3252 4950);
PAINT GREEN (-3252 4950);
DISPLAY INVISIBLE (-3252 4950);
FORCEADD TAP..1
(-3250 4900);
FORCEPROP 3 LASTPIN (-3300 4900) SIG_NAME M_J_CPU1_SA_DQ<18>
J 0
(-3290 4910);
DISPLAY 0.659574 (-3290 4910);
PAINT MONO (-3290 4910);
DISPLAY INVISIBLE (-3290 4910);
FORCEPROP 1 LASTPIN (-3300 4900) BN 18
J 0
(-3312 4908);
DISPLAY 0.489362 (-3312 4908);
PAINT GREEN (-3312 4908);
FORCEPROP 2 LAST CDS_LIB mstr_standard
J 0
(-3250 4900);
DISPLAY 0.723404 (-3250 4900);
PAINT MONO (-3250 4900);
DISPLAY INVISIBLE (-3250 4900);
FORCEPROP 1 LAST BODY_TYPE PLUMBING
J 0
(-3250 4950);
DISPLAY 0.872340 (-3250 4950);
PAINT GREEN (-3250 4950);
DISPLAY INVISIBLE (-3250 4950);
FORCEPROP 1 LAST HDL_TAP TRUE
J 0
(-2925 4775);
DISPLAY 0.872340 (-2925 4775);
DISPLAY INVISIBLE (-2925 4775);
FORCEPROP 1 LAST PATH I179
J 0
(-3252 4900);
DISPLAY 0.872340 (-3252 4900);
PAINT GREEN (-3252 4900);
DISPLAY INVISIBLE (-3252 4900);
FORCEADD TAP..1
(-3250 4850);
FORCEPROP 3 LASTPIN (-3300 4850) SIG_NAME M_J_CPU1_SA_DQ<19>
J 0
(-3290 4860);
DISPLAY 0.659574 (-3290 4860);
PAINT MONO (-3290 4860);
DISPLAY INVISIBLE (-3290 4860);
FORCEPROP 1 LASTPIN (-3300 4850) BN 19
J 0
(-3312 4858);
DISPLAY 0.489362 (-3312 4858);
PAINT GREEN (-3312 4858);
FORCEPROP 2 LAST CDS_LIB mstr_standard
J 0
(-3250 4850);
DISPLAY 0.723404 (-3250 4850);
PAINT MONO (-3250 4850);
DISPLAY INVISIBLE (-3250 4850);
FORCEPROP 1 LAST BODY_TYPE PLUMBING
J 0
(-3250 4900);
DISPLAY 0.872340 (-3250 4900);
PAINT GREEN (-3250 4900);
DISPLAY INVISIBLE (-3250 4900);
FORCEPROP 1 LAST HDL_TAP TRUE
J 0
(-2925 4725);
DISPLAY 0.872340 (-2925 4725);
DISPLAY INVISIBLE (-2925 4725);
FORCEPROP 1 LAST PATH I180
J 0
(-3252 4850);
DISPLAY 0.872340 (-3252 4850);
PAINT GREEN (-3252 4850);
DISPLAY INVISIBLE (-3252 4850);
FORCEADD TAP..1
(-3250 4800);
FORCEPROP 3 LASTPIN (-3300 4800) SIG_NAME M_J_CPU1_SA_DQ<20>
J 0
(-3290 4810);
DISPLAY 0.659574 (-3290 4810);
PAINT MONO (-3290 4810);
DISPLAY INVISIBLE (-3290 4810);
FORCEPROP 1 LASTPIN (-3300 4800) BN 20
J 0
(-3312 4808);
DISPLAY 0.489362 (-3312 4808);
PAINT GREEN (-3312 4808);
FORCEPROP 2 LAST CDS_LIB mstr_standard
J 0
(-3250 4800);
DISPLAY 0.723404 (-3250 4800);
PAINT MONO (-3250 4800);
DISPLAY INVISIBLE (-3250 4800);
FORCEPROP 1 LAST BODY_TYPE PLUMBING
J 0
(-3250 4850);
DISPLAY 0.872340 (-3250 4850);
PAINT GREEN (-3250 4850);
DISPLAY INVISIBLE (-3250 4850);
FORCEPROP 1 LAST HDL_TAP TRUE
J 0
(-2925 4675);
DISPLAY 0.872340 (-2925 4675);
DISPLAY INVISIBLE (-2925 4675);
FORCEPROP 1 LAST PATH I181
J 0
(-3252 4800);
DISPLAY 0.872340 (-3252 4800);
PAINT GREEN (-3252 4800);
DISPLAY INVISIBLE (-3252 4800);
FORCEADD TAP..1
(-3250 4750);
FORCEPROP 3 LASTPIN (-3300 4750) SIG_NAME M_J_CPU1_SA_DQ<21>
J 0
(-3290 4760);
DISPLAY 0.659574 (-3290 4760);
PAINT MONO (-3290 4760);
DISPLAY INVISIBLE (-3290 4760);
FORCEPROP 1 LASTPIN (-3300 4750) BN 21
J 0
(-3312 4758);
DISPLAY 0.489362 (-3312 4758);
PAINT GREEN (-3312 4758);
FORCEPROP 2 LAST CDS_LIB mstr_standard
J 0
(-3250 4750);
DISPLAY 0.723404 (-3250 4750);
PAINT MONO (-3250 4750);
DISPLAY INVISIBLE (-3250 4750);
FORCEPROP 1 LAST BODY_TYPE PLUMBING
J 0
(-3250 4800);
DISPLAY 0.872340 (-3250 4800);
PAINT GREEN (-3250 4800);
DISPLAY INVISIBLE (-3250 4800);
FORCEPROP 1 LAST HDL_TAP TRUE
J 0
(-2925 4625);
DISPLAY 0.872340 (-2925 4625);
DISPLAY INVISIBLE (-2925 4625);
FORCEPROP 1 LAST PATH I182
J 0
(-3252 4750);
DISPLAY 0.872340 (-3252 4750);
PAINT GREEN (-3252 4750);
DISPLAY INVISIBLE (-3252 4750);
FORCEADD TAP..1
(-3250 4650);
FORCEPROP 3 LASTPIN (-3300 4650) SIG_NAME M_J_CPU1_SA_DQ<23>
J 0
(-3290 4660);
DISPLAY 0.659574 (-3290 4660);
PAINT MONO (-3290 4660);
DISPLAY INVISIBLE (-3290 4660);
FORCEPROP 1 LASTPIN (-3300 4650) BN 23
J 0
(-3312 4658);
DISPLAY 0.489362 (-3312 4658);
PAINT GREEN (-3312 4658);
FORCEPROP 2 LAST CDS_LIB mstr_standard
J 0
(-3250 4650);
DISPLAY 0.723404 (-3250 4650);
PAINT MONO (-3250 4650);
DISPLAY INVISIBLE (-3250 4650);
FORCEPROP 1 LAST BODY_TYPE PLUMBING
J 0
(-3250 4700);
DISPLAY 0.872340 (-3250 4700);
PAINT GREEN (-3250 4700);
DISPLAY INVISIBLE (-3250 4700);
FORCEPROP 1 LAST HDL_TAP TRUE
J 0
(-2925 4525);
DISPLAY 0.872340 (-2925 4525);
DISPLAY INVISIBLE (-2925 4525);
FORCEPROP 1 LAST PATH I183
J 0
(-3252 4650);
DISPLAY 0.872340 (-3252 4650);
PAINT GREEN (-3252 4650);
DISPLAY INVISIBLE (-3252 4650);
FORCEADD TAP..1
(-3250 4700);
FORCEPROP 3 LASTPIN (-3300 4700) SIG_NAME M_J_CPU1_SA_DQ<22>
J 0
(-3290 4710);
DISPLAY 0.659574 (-3290 4710);
PAINT MONO (-3290 4710);
DISPLAY INVISIBLE (-3290 4710);
FORCEPROP 1 LASTPIN (-3300 4700) BN 22
J 0
(-3312 4708);
DISPLAY 0.489362 (-3312 4708);
PAINT GREEN (-3312 4708);
FORCEPROP 2 LAST CDS_LIB mstr_standard
J 0
(-3250 4700);
DISPLAY 0.723404 (-3250 4700);
PAINT MONO (-3250 4700);
DISPLAY INVISIBLE (-3250 4700);
FORCEPROP 1 LAST BODY_TYPE PLUMBING
J 0
(-3250 4750);
DISPLAY 0.872340 (-3250 4750);
PAINT GREEN (-3250 4750);
DISPLAY INVISIBLE (-3250 4750);
FORCEPROP 1 LAST HDL_TAP TRUE
J 0
(-2925 4575);
DISPLAY 0.872340 (-2925 4575);
DISPLAY INVISIBLE (-2925 4575);
FORCEPROP 1 LAST PATH I184
J 0
(-3252 4700);
DISPLAY 0.872340 (-3252 4700);
PAINT GREEN (-3252 4700);
DISPLAY INVISIBLE (-3252 4700);
FORCEADD TAP..1
(-3250 4500);
FORCEPROP 3 LASTPIN (-3300 4500) SIG_NAME M_J_CPU1_SA_DQ<25>
J 0
(-3290 4510);
DISPLAY 0.659574 (-3290 4510);
PAINT MONO (-3290 4510);
DISPLAY INVISIBLE (-3290 4510);
FORCEPROP 1 LASTPIN (-3300 4500) BN 25
J 0
(-3312 4508);
DISPLAY 0.489362 (-3312 4508);
PAINT GREEN (-3312 4508);
FORCEPROP 2 LAST CDS_LIB mstr_standard
J 0
(-3250 4500);
DISPLAY 0.723404 (-3250 4500);
PAINT MONO (-3250 4500);
DISPLAY INVISIBLE (-3250 4500);
FORCEPROP 1 LAST BODY_TYPE PLUMBING
J 0
(-3250 4550);
DISPLAY 0.872340 (-3250 4550);
PAINT GREEN (-3250 4550);
DISPLAY INVISIBLE (-3250 4550);
FORCEPROP 1 LAST HDL_TAP TRUE
J 0
(-2925 4375);
DISPLAY 0.872340 (-2925 4375);
DISPLAY INVISIBLE (-2925 4375);
FORCEPROP 1 LAST PATH I185
J 0
(-3252 4500);
DISPLAY 0.872340 (-3252 4500);
PAINT GREEN (-3252 4500);
DISPLAY INVISIBLE (-3252 4500);
FORCEADD TAP..1
(-3250 4550);
FORCEPROP 3 LASTPIN (-3300 4550) SIG_NAME M_J_CPU1_SA_DQ<24>
J 0
(-3290 4560);
DISPLAY 0.659574 (-3290 4560);
PAINT MONO (-3290 4560);
DISPLAY INVISIBLE (-3290 4560);
FORCEPROP 1 LASTPIN (-3300 4550) BN 24
J 0
(-3312 4558);
DISPLAY 0.489362 (-3312 4558);
PAINT GREEN (-3312 4558);
FORCEPROP 2 LAST CDS_LIB mstr_standard
J 0
(-3250 4550);
DISPLAY 0.723404 (-3250 4550);
PAINT MONO (-3250 4550);
DISPLAY INVISIBLE (-3250 4550);
FORCEPROP 1 LAST BODY_TYPE PLUMBING
J 0
(-3250 4600);
DISPLAY 0.872340 (-3250 4600);
PAINT GREEN (-3250 4600);
DISPLAY INVISIBLE (-3250 4600);
FORCEPROP 1 LAST HDL_TAP TRUE
J 0
(-2925 4425);
DISPLAY 0.872340 (-2925 4425);
DISPLAY INVISIBLE (-2925 4425);
FORCEPROP 1 LAST PATH I186
J 0
(-3252 4550);
DISPLAY 0.872340 (-3252 4550);
PAINT GREEN (-3252 4550);
DISPLAY INVISIBLE (-3252 4550);
FORCEADD TAP..1
(-3250 4450);
FORCEPROP 3 LASTPIN (-3300 4450) SIG_NAME M_J_CPU1_SA_DQ<26>
J 0
(-3290 4460);
DISPLAY 0.659574 (-3290 4460);
PAINT MONO (-3290 4460);
DISPLAY INVISIBLE (-3290 4460);
FORCEPROP 1 LASTPIN (-3300 4450) BN 26
J 0
(-3312 4458);
DISPLAY 0.489362 (-3312 4458);
PAINT GREEN (-3312 4458);
FORCEPROP 2 LAST CDS_LIB mstr_standard
J 0
(-3250 4450);
DISPLAY 0.723404 (-3250 4450);
PAINT MONO (-3250 4450);
DISPLAY INVISIBLE (-3250 4450);
FORCEPROP 1 LAST BODY_TYPE PLUMBING
J 0
(-3250 4500);
DISPLAY 0.872340 (-3250 4500);
PAINT GREEN (-3250 4500);
DISPLAY INVISIBLE (-3250 4500);
FORCEPROP 1 LAST HDL_TAP TRUE
J 0
(-2925 4325);
DISPLAY 0.872340 (-2925 4325);
DISPLAY INVISIBLE (-2925 4325);
FORCEPROP 1 LAST PATH I187
J 0
(-3252 4450);
DISPLAY 0.872340 (-3252 4450);
PAINT GREEN (-3252 4450);
DISPLAY INVISIBLE (-3252 4450);
FORCEADD TAP..1
(-3250 4400);
FORCEPROP 3 LASTPIN (-3300 4400) SIG_NAME M_J_CPU1_SA_DQ<27>
J 0
(-3290 4410);
DISPLAY 0.659574 (-3290 4410);
PAINT MONO (-3290 4410);
DISPLAY INVISIBLE (-3290 4410);
FORCEPROP 1 LASTPIN (-3300 4400) BN 27
J 0
(-3312 4408);
DISPLAY 0.489362 (-3312 4408);
PAINT GREEN (-3312 4408);
FORCEPROP 2 LAST CDS_LIB mstr_standard
J 0
(-3250 4400);
DISPLAY 0.723404 (-3250 4400);
PAINT MONO (-3250 4400);
DISPLAY INVISIBLE (-3250 4400);
FORCEPROP 1 LAST BODY_TYPE PLUMBING
J 0
(-3250 4450);
DISPLAY 0.872340 (-3250 4450);
PAINT GREEN (-3250 4450);
DISPLAY INVISIBLE (-3250 4450);
FORCEPROP 1 LAST HDL_TAP TRUE
J 0
(-2925 4275);
DISPLAY 0.872340 (-2925 4275);
DISPLAY INVISIBLE (-2925 4275);
FORCEPROP 1 LAST PATH I188
J 0
(-3252 4400);
DISPLAY 0.872340 (-3252 4400);
PAINT GREEN (-3252 4400);
DISPLAY INVISIBLE (-3252 4400);
FORCEADD TAP..1
(-3250 4350);
FORCEPROP 3 LASTPIN (-3300 4350) SIG_NAME M_J_CPU1_SA_DQ<28>
J 0
(-3290 4360);
DISPLAY 0.659574 (-3290 4360);
PAINT MONO (-3290 4360);
DISPLAY INVISIBLE (-3290 4360);
FORCEPROP 1 LASTPIN (-3300 4350) BN 28
J 0
(-3312 4358);
DISPLAY 0.489362 (-3312 4358);
PAINT GREEN (-3312 4358);
FORCEPROP 2 LAST CDS_LIB mstr_standard
J 0
(-3250 4350);
DISPLAY 0.723404 (-3250 4350);
PAINT MONO (-3250 4350);
DISPLAY INVISIBLE (-3250 4350);
FORCEPROP 1 LAST BODY_TYPE PLUMBING
J 0
(-3250 4400);
DISPLAY 0.872340 (-3250 4400);
PAINT GREEN (-3250 4400);
DISPLAY INVISIBLE (-3250 4400);
FORCEPROP 1 LAST HDL_TAP TRUE
J 0
(-2925 4225);
DISPLAY 0.872340 (-2925 4225);
DISPLAY INVISIBLE (-2925 4225);
FORCEPROP 1 LAST PATH I189
J 0
(-3252 4350);
DISPLAY 0.872340 (-3252 4350);
PAINT GREEN (-3252 4350);
DISPLAY INVISIBLE (-3252 4350);
FORCEADD TAP..1
(-3250 4300);
FORCEPROP 3 LASTPIN (-3300 4300) SIG_NAME M_J_CPU1_SA_DQ<29>
J 0
(-3290 4310);
DISPLAY 0.659574 (-3290 4310);
PAINT MONO (-3290 4310);
DISPLAY INVISIBLE (-3290 4310);
FORCEPROP 1 LASTPIN (-3300 4300) BN 29
J 0
(-3312 4308);
DISPLAY 0.489362 (-3312 4308);
PAINT GREEN (-3312 4308);
FORCEPROP 2 LAST CDS_LIB mstr_standard
J 0
(-3250 4300);
DISPLAY 0.723404 (-3250 4300);
PAINT MONO (-3250 4300);
DISPLAY INVISIBLE (-3250 4300);
FORCEPROP 1 LAST BODY_TYPE PLUMBING
J 0
(-3250 4350);
DISPLAY 0.872340 (-3250 4350);
PAINT GREEN (-3250 4350);
DISPLAY INVISIBLE (-3250 4350);
FORCEPROP 1 LAST HDL_TAP TRUE
J 0
(-2925 4175);
DISPLAY 0.872340 (-2925 4175);
DISPLAY INVISIBLE (-2925 4175);
FORCEPROP 1 LAST PATH I190
J 0
(-3252 4300);
DISPLAY 0.872340 (-3252 4300);
PAINT GREEN (-3252 4300);
DISPLAY INVISIBLE (-3252 4300);
FORCEADD TAP..1
(-3250 4250);
FORCEPROP 3 LASTPIN (-3300 4250) SIG_NAME M_J_CPU1_SA_DQ<30>
J 0
(-3290 4260);
DISPLAY 0.659574 (-3290 4260);
PAINT MONO (-3290 4260);
DISPLAY INVISIBLE (-3290 4260);
FORCEPROP 1 LASTPIN (-3300 4250) BN 30
J 0
(-3312 4258);
DISPLAY 0.489362 (-3312 4258);
PAINT GREEN (-3312 4258);
FORCEPROP 2 LAST CDS_LIB mstr_standard
J 0
(-3250 4250);
DISPLAY 0.723404 (-3250 4250);
PAINT MONO (-3250 4250);
DISPLAY INVISIBLE (-3250 4250);
FORCEPROP 1 LAST BODY_TYPE PLUMBING
J 0
(-3250 4300);
DISPLAY 0.872340 (-3250 4300);
PAINT GREEN (-3250 4300);
DISPLAY INVISIBLE (-3250 4300);
FORCEPROP 1 LAST HDL_TAP TRUE
J 0
(-2925 4125);
DISPLAY 0.872340 (-2925 4125);
DISPLAY INVISIBLE (-2925 4125);
FORCEPROP 1 LAST PATH I191
J 0
(-3252 4250);
DISPLAY 0.872340 (-3252 4250);
PAINT GREEN (-3252 4250);
DISPLAY INVISIBLE (-3252 4250);
FORCEADD TAP..1
(-3250 4100);
FORCEPROP 3 LASTPIN (-3300 4100) SIG_NAME M_J_CPU1_SB_DQ<0>
J 0
(-3290 4110);
DISPLAY 0.659574 (-3290 4110);
PAINT MONO (-3290 4110);
DISPLAY INVISIBLE (-3290 4110);
FORCEPROP 1 LASTPIN (-3300 4100) BN 0
J 0
(-3312 4108);
DISPLAY 0.489362 (-3312 4108);
PAINT GREEN (-3312 4108);
FORCEPROP 2 LAST CDS_LIB mstr_standard
J 0
(-3250 4100);
DISPLAY 0.723404 (-3250 4100);
PAINT MONO (-3250 4100);
DISPLAY INVISIBLE (-3250 4100);
FORCEPROP 1 LAST BODY_TYPE PLUMBING
J 0
(-3250 4150);
DISPLAY 0.872340 (-3250 4150);
PAINT GREEN (-3250 4150);
DISPLAY INVISIBLE (-3250 4150);
FORCEPROP 1 LAST HDL_TAP TRUE
J 0
(-2925 3975);
DISPLAY 0.872340 (-2925 3975);
DISPLAY INVISIBLE (-2925 3975);
FORCEPROP 1 LAST PATH I192
J 0
(-3252 4100);
DISPLAY 0.872340 (-3252 4100);
PAINT GREEN (-3252 4100);
DISPLAY INVISIBLE (-3252 4100);
FORCEADD TAP..1
(-3250 4200);
FORCEPROP 3 LASTPIN (-3300 4200) SIG_NAME M_J_CPU1_SA_DQ<31>
J 0
(-3290 4210);
DISPLAY 0.659574 (-3290 4210);
PAINT MONO (-3290 4210);
DISPLAY INVISIBLE (-3290 4210);
FORCEPROP 1 LASTPIN (-3300 4200) BN 31
J 0
(-3312 4208);
DISPLAY 0.489362 (-3312 4208);
PAINT GREEN (-3312 4208);
FORCEPROP 2 LAST CDS_LIB mstr_standard
J 0
(-3250 4200);
DISPLAY 0.723404 (-3250 4200);
PAINT MONO (-3250 4200);
DISPLAY INVISIBLE (-3250 4200);
FORCEPROP 1 LAST BODY_TYPE PLUMBING
J 0
(-3250 4250);
DISPLAY 0.872340 (-3250 4250);
PAINT GREEN (-3250 4250);
DISPLAY INVISIBLE (-3250 4250);
FORCEPROP 1 LAST HDL_TAP TRUE
J 0
(-2925 4075);
DISPLAY 0.872340 (-2925 4075);
DISPLAY INVISIBLE (-2925 4075);
FORCEPROP 1 LAST PATH I193
J 0
(-3252 4200);
DISPLAY 0.872340 (-3252 4200);
PAINT GREEN (-3252 4200);
DISPLAY INVISIBLE (-3252 4200);
FORCEADD OFFPAGE..3
(-2525 4125);
FORCEPROP 2 LAST $XR0 106 
J 0
(-2311 4125);
DISPLAY 0.638298 (-2311 4125);
PAINT MONO (-2311 4125);
FORCEPROP 2 LAST PATH I194
J 0
(-2300 4175);
DISPLAY 1.021277 (-2300 4175);
DISPLAY INVISIBLE (-2300 4175);
FORCEPROP 1 LAST COMMENT_BODY TRUE
J 0
(-2575 4025);
DISPLAY 0.872340 (-2575 4025);
PAINT GREEN (-2575 4025);
DISPLAY INVISIBLE (-2575 4025);
FORCEPROP 1 LAST OFFPAGE TRUE
J 0
(-2200 4000);
DISPLAY 0.872340 (-2200 4000);
PAINT GREEN (-2200 4000);
DISPLAY INVISIBLE (-2200 4000);
FORCEPROP 2 LAST CDS_LIB mstr_standard
J 0
(-2525 4125);
DISPLAY 0.723404 (-2525 4125);
PAINT MONO (-2525 4125);
DISPLAY INVISIBLE (-2525 4125);
FORCEADD OFFPAGE..6
R 2
(-2650 2350);
FORCEPROP 2 LAST $XR0 106 
J 0
(-2436 2350);
DISPLAY 0.638298 (-2436 2350);
PAINT MONO (-2436 2350);
FORCEPROP 2 LAST PATH I195
J 0
(-2425 2400);
DISPLAY 1.021277 (-2425 2400);
DISPLAY INVISIBLE (-2425 2400);
FORCEPROP 1 LAST COMMENT_BODY TRUE
J 2
(-2750 2275);
DISPLAY 0.872340 (-2750 2275);
PAINT GREEN (-2750 2275);
DISPLAY INVISIBLE (-2750 2275);
FORCEPROP 1 LAST OFFPAGE TRUE
J 2
(-2975 2225);
DISPLAY 0.872340 (-2975 2225);
PAINT GREEN (-2975 2225);
DISPLAY INVISIBLE (-2975 2225);
FORCEPROP 2 LAST CDS_LIB mstr_standard
J 2
(-2650 2350);
DISPLAY 0.723404 (-2650 2350);
PAINT MONO (-2650 2350);
DISPLAY INVISIBLE (-2650 2350);
FORCEADD TAP..1
(-3250 4000);
FORCEPROP 3 LASTPIN (-3300 4000) SIG_NAME M_J_CPU1_SB_DQ<2>
J 0
(-3290 4010);
DISPLAY 0.659574 (-3290 4010);
PAINT MONO (-3290 4010);
DISPLAY INVISIBLE (-3290 4010);
FORCEPROP 1 LASTPIN (-3300 4000) BN 2
J 0
(-3312 4008);
DISPLAY 0.489362 (-3312 4008);
PAINT GREEN (-3312 4008);
FORCEPROP 2 LAST CDS_LIB mstr_standard
J 0
(-3250 4000);
DISPLAY 0.723404 (-3250 4000);
PAINT MONO (-3250 4000);
DISPLAY INVISIBLE (-3250 4000);
FORCEPROP 1 LAST BODY_TYPE PLUMBING
J 0
(-3250 4050);
DISPLAY 0.872340 (-3250 4050);
PAINT GREEN (-3250 4050);
DISPLAY INVISIBLE (-3250 4050);
FORCEPROP 1 LAST HDL_TAP TRUE
J 0
(-2925 3875);
DISPLAY 0.872340 (-2925 3875);
DISPLAY INVISIBLE (-2925 3875);
FORCEPROP 1 LAST PATH I196
J 0
(-3252 4000);
DISPLAY 0.872340 (-3252 4000);
PAINT GREEN (-3252 4000);
DISPLAY INVISIBLE (-3252 4000);
FORCEADD TAP..1
(-3250 4050);
FORCEPROP 3 LASTPIN (-3300 4050) SIG_NAME M_J_CPU1_SB_DQ<1>
J 0
(-3290 4060);
DISPLAY 0.659574 (-3290 4060);
PAINT MONO (-3290 4060);
DISPLAY INVISIBLE (-3290 4060);
FORCEPROP 1 LASTPIN (-3300 4050) BN 1
J 0
(-3312 4058);
DISPLAY 0.489362 (-3312 4058);
PAINT GREEN (-3312 4058);
FORCEPROP 2 LAST CDS_LIB mstr_standard
J 0
(-3250 4050);
DISPLAY 0.723404 (-3250 4050);
PAINT MONO (-3250 4050);
DISPLAY INVISIBLE (-3250 4050);
FORCEPROP 1 LAST BODY_TYPE PLUMBING
J 0
(-3250 4100);
DISPLAY 0.872340 (-3250 4100);
PAINT GREEN (-3250 4100);
DISPLAY INVISIBLE (-3250 4100);
FORCEPROP 1 LAST HDL_TAP TRUE
J 0
(-2925 3925);
DISPLAY 0.872340 (-2925 3925);
DISPLAY INVISIBLE (-2925 3925);
FORCEPROP 1 LAST PATH I197
J 0
(-3252 4050);
DISPLAY 0.872340 (-3252 4050);
PAINT GREEN (-3252 4050);
DISPLAY INVISIBLE (-3252 4050);
FORCEADD TAP..1
(-3250 3900);
FORCEPROP 3 LASTPIN (-3300 3900) SIG_NAME M_J_CPU1_SB_DQ<4>
J 0
(-3290 3910);
DISPLAY 0.659574 (-3290 3910);
PAINT MONO (-3290 3910);
DISPLAY INVISIBLE (-3290 3910);
FORCEPROP 1 LASTPIN (-3300 3900) BN 4
J 0
(-3312 3908);
DISPLAY 0.489362 (-3312 3908);
PAINT GREEN (-3312 3908);
FORCEPROP 2 LAST CDS_LIB mstr_standard
J 0
(-3250 3900);
DISPLAY 0.723404 (-3250 3900);
PAINT MONO (-3250 3900);
DISPLAY INVISIBLE (-3250 3900);
FORCEPROP 1 LAST BODY_TYPE PLUMBING
J 0
(-3250 3950);
DISPLAY 0.872340 (-3250 3950);
PAINT GREEN (-3250 3950);
DISPLAY INVISIBLE (-3250 3950);
FORCEPROP 1 LAST HDL_TAP TRUE
J 0
(-2925 3775);
DISPLAY 0.872340 (-2925 3775);
DISPLAY INVISIBLE (-2925 3775);
FORCEPROP 1 LAST PATH I198
J 0
(-3252 3900);
DISPLAY 0.872340 (-3252 3900);
PAINT GREEN (-3252 3900);
DISPLAY INVISIBLE (-3252 3900);
FORCEADD TAP..1
(-3250 3950);
FORCEPROP 3 LASTPIN (-3300 3950) SIG_NAME M_J_CPU1_SB_DQ<3>
J 0
(-3290 3960);
DISPLAY 0.659574 (-3290 3960);
PAINT MONO (-3290 3960);
DISPLAY INVISIBLE (-3290 3960);
FORCEPROP 1 LASTPIN (-3300 3950) BN 3
J 0
(-3312 3958);
DISPLAY 0.489362 (-3312 3958);
PAINT GREEN (-3312 3958);
FORCEPROP 2 LAST CDS_LIB mstr_standard
J 0
(-3250 3950);
DISPLAY 0.723404 (-3250 3950);
PAINT MONO (-3250 3950);
DISPLAY INVISIBLE (-3250 3950);
FORCEPROP 1 LAST BODY_TYPE PLUMBING
J 0
(-3250 4000);
DISPLAY 0.872340 (-3250 4000);
PAINT GREEN (-3250 4000);
DISPLAY INVISIBLE (-3250 4000);
FORCEPROP 1 LAST HDL_TAP TRUE
J 0
(-2925 3825);
DISPLAY 0.872340 (-2925 3825);
DISPLAY INVISIBLE (-2925 3825);
FORCEPROP 1 LAST PATH I199
J 0
(-3252 3950);
DISPLAY 0.872340 (-3252 3950);
PAINT GREEN (-3252 3950);
DISPLAY INVISIBLE (-3252 3950);
FORCEADD TAP..1
(-3250 3850);
FORCEPROP 3 LASTPIN (-3300 3850) SIG_NAME M_J_CPU1_SB_DQ<5>
J 0
(-3290 3860);
DISPLAY 0.659574 (-3290 3860);
PAINT MONO (-3290 3860);
DISPLAY INVISIBLE (-3290 3860);
FORCEPROP 1 LASTPIN (-3300 3850) BN 5
J 0
(-3312 3858);
DISPLAY 0.489362 (-3312 3858);
PAINT GREEN (-3312 3858);
FORCEPROP 2 LAST CDS_LIB mstr_standard
J 0
(-3250 3850);
DISPLAY 0.723404 (-3250 3850);
PAINT MONO (-3250 3850);
DISPLAY INVISIBLE (-3250 3850);
FORCEPROP 1 LAST BODY_TYPE PLUMBING
J 0
(-3250 3900);
DISPLAY 0.872340 (-3250 3900);
PAINT GREEN (-3250 3900);
DISPLAY INVISIBLE (-3250 3900);
FORCEPROP 1 LAST HDL_TAP TRUE
J 0
(-2925 3725);
DISPLAY 0.872340 (-2925 3725);
DISPLAY INVISIBLE (-2925 3725);
FORCEPROP 1 LAST PATH I200
J 0
(-3252 3850);
DISPLAY 0.872340 (-3252 3850);
PAINT GREEN (-3252 3850);
DISPLAY INVISIBLE (-3252 3850);
FORCEADD TAP..1
(-3250 3750);
FORCEPROP 3 LASTPIN (-3300 3750) SIG_NAME M_J_CPU1_SB_DQ<7>
J 0
(-3290 3760);
DISPLAY 0.659574 (-3290 3760);
PAINT MONO (-3290 3760);
DISPLAY INVISIBLE (-3290 3760);
FORCEPROP 1 LASTPIN (-3300 3750) BN 7
J 0
(-3312 3758);
DISPLAY 0.489362 (-3312 3758);
PAINT GREEN (-3312 3758);
FORCEPROP 2 LAST CDS_LIB mstr_standard
J 0
(-3250 3750);
DISPLAY 0.723404 (-3250 3750);
PAINT MONO (-3250 3750);
DISPLAY INVISIBLE (-3250 3750);
FORCEPROP 1 LAST BODY_TYPE PLUMBING
J 0
(-3250 3800);
DISPLAY 0.872340 (-3250 3800);
PAINT GREEN (-3250 3800);
DISPLAY INVISIBLE (-3250 3800);
FORCEPROP 1 LAST HDL_TAP TRUE
J 0
(-2925 3625);
DISPLAY 0.872340 (-2925 3625);
DISPLAY INVISIBLE (-2925 3625);
FORCEPROP 1 LAST PATH I201
J 0
(-3252 3750);
DISPLAY 0.872340 (-3252 3750);
PAINT GREEN (-3252 3750);
DISPLAY INVISIBLE (-3252 3750);
FORCEADD TAP..1
(-3250 3800);
FORCEPROP 3 LASTPIN (-3300 3800) SIG_NAME M_J_CPU1_SB_DQ<6>
J 0
(-3290 3810);
DISPLAY 0.659574 (-3290 3810);
PAINT MONO (-3290 3810);
DISPLAY INVISIBLE (-3290 3810);
FORCEPROP 1 LASTPIN (-3300 3800) BN 6
J 0
(-3312 3808);
DISPLAY 0.489362 (-3312 3808);
PAINT GREEN (-3312 3808);
FORCEPROP 2 LAST CDS_LIB mstr_standard
J 0
(-3250 3800);
DISPLAY 0.723404 (-3250 3800);
PAINT MONO (-3250 3800);
DISPLAY INVISIBLE (-3250 3800);
FORCEPROP 1 LAST BODY_TYPE PLUMBING
J 0
(-3250 3850);
DISPLAY 0.872340 (-3250 3850);
PAINT GREEN (-3250 3850);
DISPLAY INVISIBLE (-3250 3850);
FORCEPROP 1 LAST HDL_TAP TRUE
J 0
(-2925 3675);
DISPLAY 0.872340 (-2925 3675);
DISPLAY INVISIBLE (-2925 3675);
FORCEPROP 1 LAST PATH I202
J 0
(-3252 3800);
DISPLAY 0.872340 (-3252 3800);
PAINT GREEN (-3252 3800);
DISPLAY INVISIBLE (-3252 3800);
FORCEADD TAP..1
(-3250 3650);
FORCEPROP 3 LASTPIN (-3300 3650) SIG_NAME M_J_CPU1_SB_DQ<8>
J 0
(-3290 3660);
DISPLAY 0.659574 (-3290 3660);
PAINT MONO (-3290 3660);
DISPLAY INVISIBLE (-3290 3660);
FORCEPROP 1 LASTPIN (-3300 3650) BN 8
J 0
(-3312 3658);
DISPLAY 0.489362 (-3312 3658);
PAINT GREEN (-3312 3658);
FORCEPROP 2 LAST CDS_LIB mstr_standard
J 0
(-3250 3650);
DISPLAY 0.723404 (-3250 3650);
PAINT MONO (-3250 3650);
DISPLAY INVISIBLE (-3250 3650);
FORCEPROP 1 LAST BODY_TYPE PLUMBING
J 0
(-3250 3700);
DISPLAY 0.872340 (-3250 3700);
PAINT GREEN (-3250 3700);
DISPLAY INVISIBLE (-3250 3700);
FORCEPROP 1 LAST HDL_TAP TRUE
J 0
(-2925 3525);
DISPLAY 0.872340 (-2925 3525);
DISPLAY INVISIBLE (-2925 3525);
FORCEPROP 1 LAST PATH I203
J 0
(-3252 3650);
DISPLAY 0.872340 (-3252 3650);
PAINT GREEN (-3252 3650);
DISPLAY INVISIBLE (-3252 3650);
FORCEADD TAP..1
(-3250 3600);
FORCEPROP 3 LASTPIN (-3300 3600) SIG_NAME M_J_CPU1_SB_DQ<9>
J 0
(-3290 3610);
DISPLAY 0.659574 (-3290 3610);
PAINT MONO (-3290 3610);
DISPLAY INVISIBLE (-3290 3610);
FORCEPROP 1 LASTPIN (-3300 3600) BN 9
J 0
(-3312 3608);
DISPLAY 0.489362 (-3312 3608);
PAINT GREEN (-3312 3608);
FORCEPROP 2 LAST CDS_LIB mstr_standard
J 0
(-3250 3600);
DISPLAY 0.723404 (-3250 3600);
PAINT MONO (-3250 3600);
DISPLAY INVISIBLE (-3250 3600);
FORCEPROP 1 LAST BODY_TYPE PLUMBING
J 0
(-3250 3650);
DISPLAY 0.872340 (-3250 3650);
PAINT GREEN (-3250 3650);
DISPLAY INVISIBLE (-3250 3650);
FORCEPROP 1 LAST HDL_TAP TRUE
J 0
(-2925 3475);
DISPLAY 0.872340 (-2925 3475);
DISPLAY INVISIBLE (-2925 3475);
FORCEPROP 1 LAST PATH I204
J 0
(-3252 3600);
DISPLAY 0.872340 (-3252 3600);
PAINT GREEN (-3252 3600);
DISPLAY INVISIBLE (-3252 3600);
FORCEADD TAP..1
(-3250 3500);
FORCEPROP 3 LASTPIN (-3300 3500) SIG_NAME M_J_CPU1_SB_DQ<11>
J 0
(-3290 3510);
DISPLAY 0.659574 (-3290 3510);
PAINT MONO (-3290 3510);
DISPLAY INVISIBLE (-3290 3510);
FORCEPROP 1 LASTPIN (-3300 3500) BN 11
J 0
(-3312 3508);
DISPLAY 0.489362 (-3312 3508);
PAINT GREEN (-3312 3508);
FORCEPROP 2 LAST CDS_LIB mstr_standard
J 0
(-3250 3500);
DISPLAY 0.723404 (-3250 3500);
PAINT MONO (-3250 3500);
DISPLAY INVISIBLE (-3250 3500);
FORCEPROP 1 LAST BODY_TYPE PLUMBING
J 0
(-3250 3550);
DISPLAY 0.872340 (-3250 3550);
PAINT GREEN (-3250 3550);
DISPLAY INVISIBLE (-3250 3550);
FORCEPROP 1 LAST HDL_TAP TRUE
J 0
(-2925 3375);
DISPLAY 0.872340 (-2925 3375);
DISPLAY INVISIBLE (-2925 3375);
FORCEPROP 1 LAST PATH I205
J 0
(-3252 3500);
DISPLAY 0.872340 (-3252 3500);
PAINT GREEN (-3252 3500);
DISPLAY INVISIBLE (-3252 3500);
FORCEADD TAP..1
(-3250 3550);
FORCEPROP 3 LASTPIN (-3300 3550) SIG_NAME M_J_CPU1_SB_DQ<10>
J 0
(-3290 3560);
DISPLAY 0.659574 (-3290 3560);
PAINT MONO (-3290 3560);
DISPLAY INVISIBLE (-3290 3560);
FORCEPROP 1 LASTPIN (-3300 3550) BN 10
J 0
(-3312 3558);
DISPLAY 0.489362 (-3312 3558);
PAINT GREEN (-3312 3558);
FORCEPROP 2 LAST CDS_LIB mstr_standard
J 0
(-3250 3550);
DISPLAY 0.723404 (-3250 3550);
PAINT MONO (-3250 3550);
DISPLAY INVISIBLE (-3250 3550);
FORCEPROP 1 LAST BODY_TYPE PLUMBING
J 0
(-3250 3600);
DISPLAY 0.872340 (-3250 3600);
PAINT GREEN (-3250 3600);
DISPLAY INVISIBLE (-3250 3600);
FORCEPROP 1 LAST HDL_TAP TRUE
J 0
(-2925 3425);
DISPLAY 0.872340 (-2925 3425);
DISPLAY INVISIBLE (-2925 3425);
FORCEPROP 1 LAST PATH I206
J 0
(-3252 3550);
DISPLAY 0.872340 (-3252 3550);
PAINT GREEN (-3252 3550);
DISPLAY INVISIBLE (-3252 3550);
FORCEADD TAP..1
(-3250 3450);
FORCEPROP 3 LASTPIN (-3300 3450) SIG_NAME M_J_CPU1_SB_DQ<12>
J 0
(-3290 3460);
DISPLAY 0.659574 (-3290 3460);
PAINT MONO (-3290 3460);
DISPLAY INVISIBLE (-3290 3460);
FORCEPROP 1 LASTPIN (-3300 3450) BN 12
J 0
(-3312 3458);
DISPLAY 0.489362 (-3312 3458);
PAINT GREEN (-3312 3458);
FORCEPROP 2 LAST CDS_LIB mstr_standard
J 0
(-3250 3450);
DISPLAY 0.723404 (-3250 3450);
PAINT MONO (-3250 3450);
DISPLAY INVISIBLE (-3250 3450);
FORCEPROP 1 LAST BODY_TYPE PLUMBING
J 0
(-3250 3500);
DISPLAY 0.872340 (-3250 3500);
PAINT GREEN (-3250 3500);
DISPLAY INVISIBLE (-3250 3500);
FORCEPROP 1 LAST HDL_TAP TRUE
J 0
(-2925 3325);
DISPLAY 0.872340 (-2925 3325);
DISPLAY INVISIBLE (-2925 3325);
FORCEPROP 1 LAST PATH I207
J 0
(-3252 3450);
DISPLAY 0.872340 (-3252 3450);
PAINT GREEN (-3252 3450);
DISPLAY INVISIBLE (-3252 3450);
FORCEADD TAP..1
(-3250 3400);
FORCEPROP 3 LASTPIN (-3300 3400) SIG_NAME M_J_CPU1_SB_DQ<13>
J 0
(-3290 3410);
DISPLAY 0.659574 (-3290 3410);
PAINT MONO (-3290 3410);
DISPLAY INVISIBLE (-3290 3410);
FORCEPROP 1 LASTPIN (-3300 3400) BN 13
J 0
(-3312 3408);
DISPLAY 0.489362 (-3312 3408);
PAINT GREEN (-3312 3408);
FORCEPROP 2 LAST CDS_LIB mstr_standard
J 0
(-3250 3400);
DISPLAY 0.723404 (-3250 3400);
PAINT MONO (-3250 3400);
DISPLAY INVISIBLE (-3250 3400);
FORCEPROP 1 LAST BODY_TYPE PLUMBING
J 0
(-3250 3450);
DISPLAY 0.872340 (-3250 3450);
PAINT GREEN (-3250 3450);
DISPLAY INVISIBLE (-3250 3450);
FORCEPROP 1 LAST HDL_TAP TRUE
J 0
(-2925 3275);
DISPLAY 0.872340 (-2925 3275);
DISPLAY INVISIBLE (-2925 3275);
FORCEPROP 1 LAST PATH I208
J 0
(-3252 3400);
DISPLAY 0.872340 (-3252 3400);
PAINT GREEN (-3252 3400);
DISPLAY INVISIBLE (-3252 3400);
FORCEADD TAP..1
(-3250 3350);
FORCEPROP 3 LASTPIN (-3300 3350) SIG_NAME M_J_CPU1_SB_DQ<14>
J 0
(-3290 3360);
DISPLAY 0.659574 (-3290 3360);
PAINT MONO (-3290 3360);
DISPLAY INVISIBLE (-3290 3360);
FORCEPROP 1 LASTPIN (-3300 3350) BN 14
J 0
(-3312 3358);
DISPLAY 0.489362 (-3312 3358);
PAINT GREEN (-3312 3358);
FORCEPROP 2 LAST CDS_LIB mstr_standard
J 0
(-3250 3350);
DISPLAY 0.723404 (-3250 3350);
PAINT MONO (-3250 3350);
DISPLAY INVISIBLE (-3250 3350);
FORCEPROP 1 LAST BODY_TYPE PLUMBING
J 0
(-3250 3400);
DISPLAY 0.872340 (-3250 3400);
PAINT GREEN (-3250 3400);
DISPLAY INVISIBLE (-3250 3400);
FORCEPROP 1 LAST HDL_TAP TRUE
J 0
(-2925 3225);
DISPLAY 0.872340 (-2925 3225);
DISPLAY INVISIBLE (-2925 3225);
FORCEPROP 1 LAST PATH I209
J 0
(-3252 3350);
DISPLAY 0.872340 (-3252 3350);
PAINT GREEN (-3252 3350);
DISPLAY INVISIBLE (-3252 3350);
FORCEADD TAP..1
(-3250 3300);
FORCEPROP 3 LASTPIN (-3300 3300) SIG_NAME M_J_CPU1_SB_DQ<15>
J 0
(-3290 3310);
DISPLAY 0.659574 (-3290 3310);
PAINT MONO (-3290 3310);
DISPLAY INVISIBLE (-3290 3310);
FORCEPROP 1 LASTPIN (-3300 3300) BN 15
J 0
(-3312 3308);
DISPLAY 0.489362 (-3312 3308);
PAINT GREEN (-3312 3308);
FORCEPROP 2 LAST CDS_LIB mstr_standard
J 0
(-3250 3300);
DISPLAY 0.723404 (-3250 3300);
PAINT MONO (-3250 3300);
DISPLAY INVISIBLE (-3250 3300);
FORCEPROP 1 LAST BODY_TYPE PLUMBING
J 0
(-3250 3350);
DISPLAY 0.872340 (-3250 3350);
PAINT GREEN (-3250 3350);
DISPLAY INVISIBLE (-3250 3350);
FORCEPROP 1 LAST HDL_TAP TRUE
J 0
(-2925 3175);
DISPLAY 0.872340 (-2925 3175);
DISPLAY INVISIBLE (-2925 3175);
FORCEPROP 1 LAST PATH I210
J 0
(-3252 3300);
DISPLAY 0.872340 (-3252 3300);
PAINT GREEN (-3252 3300);
DISPLAY INVISIBLE (-3252 3300);
FORCEADD TAP..1
(-3250 3200);
FORCEPROP 3 LASTPIN (-3300 3200) SIG_NAME M_J_CPU1_SB_DQ<16>
J 0
(-3290 3210);
DISPLAY 0.659574 (-3290 3210);
PAINT MONO (-3290 3210);
DISPLAY INVISIBLE (-3290 3210);
FORCEPROP 1 LASTPIN (-3300 3200) BN 16
J 0
(-3312 3208);
DISPLAY 0.489362 (-3312 3208);
PAINT GREEN (-3312 3208);
FORCEPROP 2 LAST CDS_LIB mstr_standard
J 0
(-3250 3200);
DISPLAY 0.723404 (-3250 3200);
PAINT MONO (-3250 3200);
DISPLAY INVISIBLE (-3250 3200);
FORCEPROP 1 LAST BODY_TYPE PLUMBING
J 0
(-3250 3250);
DISPLAY 0.872340 (-3250 3250);
PAINT GREEN (-3250 3250);
DISPLAY INVISIBLE (-3250 3250);
FORCEPROP 1 LAST HDL_TAP TRUE
J 0
(-2925 3075);
DISPLAY 0.872340 (-2925 3075);
DISPLAY INVISIBLE (-2925 3075);
FORCEPROP 1 LAST PATH I211
J 0
(-3252 3200);
DISPLAY 0.872340 (-3252 3200);
PAINT GREEN (-3252 3200);
DISPLAY INVISIBLE (-3252 3200);
FORCEADD TAP..1
(-3250 3150);
FORCEPROP 3 LASTPIN (-3300 3150) SIG_NAME M_J_CPU1_SB_DQ<17>
J 0
(-3290 3160);
DISPLAY 0.659574 (-3290 3160);
PAINT MONO (-3290 3160);
DISPLAY INVISIBLE (-3290 3160);
FORCEPROP 1 LASTPIN (-3300 3150) BN 17
J 0
(-3312 3158);
DISPLAY 0.489362 (-3312 3158);
PAINT GREEN (-3312 3158);
FORCEPROP 2 LAST CDS_LIB mstr_standard
J 0
(-3250 3150);
DISPLAY 0.723404 (-3250 3150);
PAINT MONO (-3250 3150);
DISPLAY INVISIBLE (-3250 3150);
FORCEPROP 1 LAST BODY_TYPE PLUMBING
J 0
(-3250 3200);
DISPLAY 0.872340 (-3250 3200);
PAINT GREEN (-3250 3200);
DISPLAY INVISIBLE (-3250 3200);
FORCEPROP 1 LAST HDL_TAP TRUE
J 0
(-2925 3025);
DISPLAY 0.872340 (-2925 3025);
DISPLAY INVISIBLE (-2925 3025);
FORCEPROP 1 LAST PATH I212
J 0
(-3252 3150);
DISPLAY 0.872340 (-3252 3150);
PAINT GREEN (-3252 3150);
DISPLAY INVISIBLE (-3252 3150);
FORCEADD TAP..1
(-3250 3100);
FORCEPROP 3 LASTPIN (-3300 3100) SIG_NAME M_J_CPU1_SB_DQ<18>
J 0
(-3290 3110);
DISPLAY 0.659574 (-3290 3110);
PAINT MONO (-3290 3110);
DISPLAY INVISIBLE (-3290 3110);
FORCEPROP 1 LASTPIN (-3300 3100) BN 18
J 0
(-3312 3108);
DISPLAY 0.489362 (-3312 3108);
PAINT GREEN (-3312 3108);
FORCEPROP 2 LAST CDS_LIB mstr_standard
J 0
(-3250 3100);
DISPLAY 0.723404 (-3250 3100);
PAINT MONO (-3250 3100);
DISPLAY INVISIBLE (-3250 3100);
FORCEPROP 1 LAST BODY_TYPE PLUMBING
J 0
(-3250 3150);
DISPLAY 0.872340 (-3250 3150);
PAINT GREEN (-3250 3150);
DISPLAY INVISIBLE (-3250 3150);
FORCEPROP 1 LAST HDL_TAP TRUE
J 0
(-2925 2975);
DISPLAY 0.872340 (-2925 2975);
DISPLAY INVISIBLE (-2925 2975);
FORCEPROP 1 LAST PATH I213
J 0
(-3252 3100);
DISPLAY 0.872340 (-3252 3100);
PAINT GREEN (-3252 3100);
DISPLAY INVISIBLE (-3252 3100);
FORCEADD TAP..1
(-3250 2950);
FORCEPROP 3 LASTPIN (-3300 2950) SIG_NAME M_J_CPU1_SB_DQ<21>
J 0
(-3290 2960);
DISPLAY 0.659574 (-3290 2960);
PAINT MONO (-3290 2960);
DISPLAY INVISIBLE (-3290 2960);
FORCEPROP 1 LASTPIN (-3300 2950) BN 21
J 0
(-3312 2958);
DISPLAY 0.489362 (-3312 2958);
PAINT GREEN (-3312 2958);
FORCEPROP 2 LAST CDS_LIB mstr_standard
J 0
(-3250 2950);
DISPLAY 0.723404 (-3250 2950);
PAINT MONO (-3250 2950);
DISPLAY INVISIBLE (-3250 2950);
FORCEPROP 1 LAST BODY_TYPE PLUMBING
J 0
(-3250 3000);
DISPLAY 0.872340 (-3250 3000);
PAINT GREEN (-3250 3000);
DISPLAY INVISIBLE (-3250 3000);
FORCEPROP 1 LAST HDL_TAP TRUE
J 0
(-2925 2825);
DISPLAY 0.872340 (-2925 2825);
DISPLAY INVISIBLE (-2925 2825);
FORCEPROP 1 LAST PATH I214
J 0
(-3252 2950);
DISPLAY 0.872340 (-3252 2950);
PAINT GREEN (-3252 2950);
DISPLAY INVISIBLE (-3252 2950);
FORCEADD TAP..1
(-3250 3000);
FORCEPROP 3 LASTPIN (-3300 3000) SIG_NAME M_J_CPU1_SB_DQ<20>
J 0
(-3290 3010);
DISPLAY 0.659574 (-3290 3010);
PAINT MONO (-3290 3010);
DISPLAY INVISIBLE (-3290 3010);
FORCEPROP 1 LASTPIN (-3300 3000) BN 20
J 0
(-3312 3008);
DISPLAY 0.489362 (-3312 3008);
PAINT GREEN (-3312 3008);
FORCEPROP 2 LAST CDS_LIB mstr_standard
J 0
(-3250 3000);
DISPLAY 0.723404 (-3250 3000);
PAINT MONO (-3250 3000);
DISPLAY INVISIBLE (-3250 3000);
FORCEPROP 1 LAST BODY_TYPE PLUMBING
J 0
(-3250 3050);
DISPLAY 0.872340 (-3250 3050);
PAINT GREEN (-3250 3050);
DISPLAY INVISIBLE (-3250 3050);
FORCEPROP 1 LAST HDL_TAP TRUE
J 0
(-2925 2875);
DISPLAY 0.872340 (-2925 2875);
DISPLAY INVISIBLE (-2925 2875);
FORCEPROP 1 LAST PATH I215
J 0
(-3252 3000);
DISPLAY 0.872340 (-3252 3000);
PAINT GREEN (-3252 3000);
DISPLAY INVISIBLE (-3252 3000);
FORCEADD TAP..1
(-3250 3050);
FORCEPROP 3 LASTPIN (-3300 3050) SIG_NAME M_J_CPU1_SB_DQ<19>
J 0
(-3290 3060);
DISPLAY 0.659574 (-3290 3060);
PAINT MONO (-3290 3060);
DISPLAY INVISIBLE (-3290 3060);
FORCEPROP 1 LASTPIN (-3300 3050) BN 19
J 0
(-3312 3058);
DISPLAY 0.489362 (-3312 3058);
PAINT GREEN (-3312 3058);
FORCEPROP 2 LAST CDS_LIB mstr_standard
J 0
(-3250 3050);
DISPLAY 0.723404 (-3250 3050);
PAINT MONO (-3250 3050);
DISPLAY INVISIBLE (-3250 3050);
FORCEPROP 1 LAST BODY_TYPE PLUMBING
J 0
(-3250 3100);
DISPLAY 0.872340 (-3250 3100);
PAINT GREEN (-3250 3100);
DISPLAY INVISIBLE (-3250 3100);
FORCEPROP 1 LAST HDL_TAP TRUE
J 0
(-2925 2925);
DISPLAY 0.872340 (-2925 2925);
DISPLAY INVISIBLE (-2925 2925);
FORCEPROP 1 LAST PATH I216
J 0
(-3252 3050);
DISPLAY 0.872340 (-3252 3050);
PAINT GREEN (-3252 3050);
DISPLAY INVISIBLE (-3252 3050);
FORCEADD TAP..1
(-3250 2900);
FORCEPROP 3 LASTPIN (-3300 2900) SIG_NAME M_J_CPU1_SB_DQ<22>
J 0
(-3290 2910);
DISPLAY 0.659574 (-3290 2910);
PAINT MONO (-3290 2910);
DISPLAY INVISIBLE (-3290 2910);
FORCEPROP 1 LASTPIN (-3300 2900) BN 22
J 0
(-3312 2908);
DISPLAY 0.489362 (-3312 2908);
PAINT GREEN (-3312 2908);
FORCEPROP 2 LAST CDS_LIB mstr_standard
J 0
(-3250 2900);
DISPLAY 0.723404 (-3250 2900);
PAINT MONO (-3250 2900);
DISPLAY INVISIBLE (-3250 2900);
FORCEPROP 1 LAST BODY_TYPE PLUMBING
J 0
(-3250 2950);
DISPLAY 0.872340 (-3250 2950);
PAINT GREEN (-3250 2950);
DISPLAY INVISIBLE (-3250 2950);
FORCEPROP 1 LAST HDL_TAP TRUE
J 0
(-2925 2775);
DISPLAY 0.872340 (-2925 2775);
DISPLAY INVISIBLE (-2925 2775);
FORCEPROP 1 LAST PATH I217
J 0
(-3252 2900);
DISPLAY 0.872340 (-3252 2900);
PAINT GREEN (-3252 2900);
DISPLAY INVISIBLE (-3252 2900);
FORCEADD TAP..1
(-3250 2850);
FORCEPROP 3 LASTPIN (-3300 2850) SIG_NAME M_J_CPU1_SB_DQ<23>
J 0
(-3290 2860);
DISPLAY 0.659574 (-3290 2860);
PAINT MONO (-3290 2860);
DISPLAY INVISIBLE (-3290 2860);
FORCEPROP 1 LASTPIN (-3300 2850) BN 23
J 0
(-3312 2858);
DISPLAY 0.489362 (-3312 2858);
PAINT GREEN (-3312 2858);
FORCEPROP 2 LAST CDS_LIB mstr_standard
J 0
(-3250 2850);
DISPLAY 0.723404 (-3250 2850);
PAINT MONO (-3250 2850);
DISPLAY INVISIBLE (-3250 2850);
FORCEPROP 1 LAST BODY_TYPE PLUMBING
J 0
(-3250 2900);
DISPLAY 0.872340 (-3250 2900);
PAINT GREEN (-3250 2900);
DISPLAY INVISIBLE (-3250 2900);
FORCEPROP 1 LAST HDL_TAP TRUE
J 0
(-2925 2725);
DISPLAY 0.872340 (-2925 2725);
DISPLAY INVISIBLE (-2925 2725);
FORCEPROP 1 LAST PATH I218
J 0
(-3252 2850);
DISPLAY 0.872340 (-3252 2850);
PAINT GREEN (-3252 2850);
DISPLAY INVISIBLE (-3252 2850);
FORCEADD TAP..1
(-3250 2700);
FORCEPROP 3 LASTPIN (-3300 2700) SIG_NAME M_J_CPU1_SB_DQ<25>
J 0
(-3290 2710);
DISPLAY 0.659574 (-3290 2710);
PAINT MONO (-3290 2710);
DISPLAY INVISIBLE (-3290 2710);
FORCEPROP 1 LASTPIN (-3300 2700) BN 25
J 0
(-3312 2708);
DISPLAY 0.489362 (-3312 2708);
PAINT GREEN (-3312 2708);
FORCEPROP 2 LAST CDS_LIB mstr_standard
J 0
(-3250 2700);
DISPLAY 0.723404 (-3250 2700);
PAINT MONO (-3250 2700);
DISPLAY INVISIBLE (-3250 2700);
FORCEPROP 1 LAST BODY_TYPE PLUMBING
J 0
(-3250 2750);
DISPLAY 0.872340 (-3250 2750);
PAINT GREEN (-3250 2750);
DISPLAY INVISIBLE (-3250 2750);
FORCEPROP 1 LAST HDL_TAP TRUE
J 0
(-2925 2575);
DISPLAY 0.872340 (-2925 2575);
DISPLAY INVISIBLE (-2925 2575);
FORCEPROP 1 LAST PATH I219
J 0
(-3252 2700);
DISPLAY 0.872340 (-3252 2700);
PAINT GREEN (-3252 2700);
DISPLAY INVISIBLE (-3252 2700);
FORCEADD TAP..1
(-3250 2750);
FORCEPROP 3 LASTPIN (-3300 2750) SIG_NAME M_J_CPU1_SB_DQ<24>
J 0
(-3290 2760);
DISPLAY 0.659574 (-3290 2760);
PAINT MONO (-3290 2760);
DISPLAY INVISIBLE (-3290 2760);
FORCEPROP 1 LASTPIN (-3300 2750) BN 24
J 0
(-3312 2758);
DISPLAY 0.489362 (-3312 2758);
PAINT GREEN (-3312 2758);
FORCEPROP 2 LAST CDS_LIB mstr_standard
J 0
(-3250 2750);
DISPLAY 0.723404 (-3250 2750);
PAINT MONO (-3250 2750);
DISPLAY INVISIBLE (-3250 2750);
FORCEPROP 1 LAST BODY_TYPE PLUMBING
J 0
(-3250 2800);
DISPLAY 0.872340 (-3250 2800);
PAINT GREEN (-3250 2800);
DISPLAY INVISIBLE (-3250 2800);
FORCEPROP 1 LAST HDL_TAP TRUE
J 0
(-2925 2625);
DISPLAY 0.872340 (-2925 2625);
DISPLAY INVISIBLE (-2925 2625);
FORCEPROP 1 LAST PATH I220
J 0
(-3252 2750);
DISPLAY 0.872340 (-3252 2750);
PAINT GREEN (-3252 2750);
DISPLAY INVISIBLE (-3252 2750);
FORCEADD TAP..1
(-3250 2650);
FORCEPROP 3 LASTPIN (-3300 2650) SIG_NAME M_J_CPU1_SB_DQ<26>
J 0
(-3290 2660);
DISPLAY 0.659574 (-3290 2660);
PAINT MONO (-3290 2660);
DISPLAY INVISIBLE (-3290 2660);
FORCEPROP 1 LASTPIN (-3300 2650) BN 26
J 0
(-3312 2658);
DISPLAY 0.489362 (-3312 2658);
PAINT GREEN (-3312 2658);
FORCEPROP 2 LAST CDS_LIB mstr_standard
J 0
(-3250 2650);
DISPLAY 0.723404 (-3250 2650);
PAINT MONO (-3250 2650);
DISPLAY INVISIBLE (-3250 2650);
FORCEPROP 1 LAST BODY_TYPE PLUMBING
J 0
(-3250 2700);
DISPLAY 0.872340 (-3250 2700);
PAINT GREEN (-3250 2700);
DISPLAY INVISIBLE (-3250 2700);
FORCEPROP 1 LAST HDL_TAP TRUE
J 0
(-2925 2525);
DISPLAY 0.872340 (-2925 2525);
DISPLAY INVISIBLE (-2925 2525);
FORCEPROP 1 LAST PATH I221
J 0
(-3252 2650);
DISPLAY 0.872340 (-3252 2650);
PAINT GREEN (-3252 2650);
DISPLAY INVISIBLE (-3252 2650);
FORCEADD TAP..1
(-3250 2600);
FORCEPROP 3 LASTPIN (-3300 2600) SIG_NAME M_J_CPU1_SB_DQ<27>
J 0
(-3290 2610);
DISPLAY 0.659574 (-3290 2610);
PAINT MONO (-3290 2610);
DISPLAY INVISIBLE (-3290 2610);
FORCEPROP 1 LASTPIN (-3300 2600) BN 27
J 0
(-3312 2608);
DISPLAY 0.489362 (-3312 2608);
PAINT GREEN (-3312 2608);
FORCEPROP 2 LAST CDS_LIB mstr_standard
J 0
(-3250 2600);
DISPLAY 0.723404 (-3250 2600);
PAINT MONO (-3250 2600);
DISPLAY INVISIBLE (-3250 2600);
FORCEPROP 1 LAST BODY_TYPE PLUMBING
J 0
(-3250 2650);
DISPLAY 0.872340 (-3250 2650);
PAINT GREEN (-3250 2650);
DISPLAY INVISIBLE (-3250 2650);
FORCEPROP 1 LAST HDL_TAP TRUE
J 0
(-2925 2475);
DISPLAY 0.872340 (-2925 2475);
DISPLAY INVISIBLE (-2925 2475);
FORCEPROP 1 LAST PATH I222
J 0
(-3252 2600);
DISPLAY 0.872340 (-3252 2600);
PAINT GREEN (-3252 2600);
DISPLAY INVISIBLE (-3252 2600);
FORCEADD TAP..1
(-3250 2450);
FORCEPROP 3 LASTPIN (-3300 2450) SIG_NAME M_J_CPU1_SB_DQ<30>
J 0
(-3290 2460);
DISPLAY 0.659574 (-3290 2460);
PAINT MONO (-3290 2460);
DISPLAY INVISIBLE (-3290 2460);
FORCEPROP 1 LASTPIN (-3300 2450) BN 30
J 0
(-3312 2458);
DISPLAY 0.489362 (-3312 2458);
PAINT GREEN (-3312 2458);
FORCEPROP 2 LAST CDS_LIB mstr_standard
J 0
(-3250 2450);
DISPLAY 0.723404 (-3250 2450);
PAINT MONO (-3250 2450);
DISPLAY INVISIBLE (-3250 2450);
FORCEPROP 1 LAST BODY_TYPE PLUMBING
J 0
(-3250 2500);
DISPLAY 0.872340 (-3250 2500);
PAINT GREEN (-3250 2500);
DISPLAY INVISIBLE (-3250 2500);
FORCEPROP 1 LAST HDL_TAP TRUE
J 0
(-2925 2325);
DISPLAY 0.872340 (-2925 2325);
DISPLAY INVISIBLE (-2925 2325);
FORCEPROP 1 LAST PATH I223
J 0
(-3252 2450);
DISPLAY 0.872340 (-3252 2450);
PAINT GREEN (-3252 2450);
DISPLAY INVISIBLE (-3252 2450);
FORCEADD TAP..1
(-3250 2550);
FORCEPROP 3 LASTPIN (-3300 2550) SIG_NAME M_J_CPU1_SB_DQ<28>
J 0
(-3290 2560);
DISPLAY 0.659574 (-3290 2560);
PAINT MONO (-3290 2560);
DISPLAY INVISIBLE (-3290 2560);
FORCEPROP 1 LASTPIN (-3300 2550) BN 28
J 0
(-3312 2558);
DISPLAY 0.489362 (-3312 2558);
PAINT GREEN (-3312 2558);
FORCEPROP 2 LAST CDS_LIB mstr_standard
J 0
(-3250 2550);
DISPLAY 0.723404 (-3250 2550);
PAINT MONO (-3250 2550);
DISPLAY INVISIBLE (-3250 2550);
FORCEPROP 1 LAST BODY_TYPE PLUMBING
J 0
(-3250 2600);
DISPLAY 0.872340 (-3250 2600);
PAINT GREEN (-3250 2600);
DISPLAY INVISIBLE (-3250 2600);
FORCEPROP 1 LAST HDL_TAP TRUE
J 0
(-2925 2425);
DISPLAY 0.872340 (-2925 2425);
DISPLAY INVISIBLE (-2925 2425);
FORCEPROP 1 LAST PATH I224
J 0
(-3252 2550);
DISPLAY 0.872340 (-3252 2550);
PAINT GREEN (-3252 2550);
DISPLAY INVISIBLE (-3252 2550);
FORCEADD TAP..1
(-3250 2500);
FORCEPROP 3 LASTPIN (-3300 2500) SIG_NAME M_J_CPU1_SB_DQ<29>
J 0
(-3290 2510);
DISPLAY 0.659574 (-3290 2510);
PAINT MONO (-3290 2510);
DISPLAY INVISIBLE (-3290 2510);
FORCEPROP 1 LASTPIN (-3300 2500) BN 29
J 0
(-3312 2508);
DISPLAY 0.489362 (-3312 2508);
PAINT GREEN (-3312 2508);
FORCEPROP 2 LAST CDS_LIB mstr_standard
J 0
(-3250 2500);
DISPLAY 0.723404 (-3250 2500);
PAINT MONO (-3250 2500);
DISPLAY INVISIBLE (-3250 2500);
FORCEPROP 1 LAST BODY_TYPE PLUMBING
J 0
(-3250 2550);
DISPLAY 0.872340 (-3250 2550);
PAINT GREEN (-3250 2550);
DISPLAY INVISIBLE (-3250 2550);
FORCEPROP 1 LAST HDL_TAP TRUE
J 0
(-2925 2375);
DISPLAY 0.872340 (-2925 2375);
DISPLAY INVISIBLE (-2925 2375);
FORCEPROP 1 LAST PATH I225
J 0
(-3252 2500);
DISPLAY 0.872340 (-3252 2500);
PAINT GREEN (-3252 2500);
DISPLAY INVISIBLE (-3252 2500);
FORCEADD TAP..1
(-3250 2400);
FORCEPROP 3 LASTPIN (-3300 2400) SIG_NAME M_J_CPU1_SB_DQ<31>
J 0
(-3290 2410);
DISPLAY 0.659574 (-3290 2410);
PAINT MONO (-3290 2410);
DISPLAY INVISIBLE (-3290 2410);
FORCEPROP 1 LASTPIN (-3300 2400) BN 31
J 0
(-3312 2408);
DISPLAY 0.489362 (-3312 2408);
PAINT GREEN (-3312 2408);
FORCEPROP 2 LAST CDS_LIB mstr_standard
J 0
(-3250 2400);
DISPLAY 0.723404 (-3250 2400);
PAINT MONO (-3250 2400);
DISPLAY INVISIBLE (-3250 2400);
FORCEPROP 1 LAST BODY_TYPE PLUMBING
J 0
(-3250 2450);
DISPLAY 0.872340 (-3250 2450);
PAINT GREEN (-3250 2450);
DISPLAY INVISIBLE (-3250 2450);
FORCEPROP 1 LAST HDL_TAP TRUE
J 0
(-2925 2275);
DISPLAY 0.872340 (-2925 2275);
DISPLAY INVISIBLE (-2925 2275);
FORCEPROP 1 LAST PATH I226
J 0
(-3252 2400);
DISPLAY 0.872340 (-3252 2400);
PAINT GREEN (-3252 2400);
DISPLAY INVISIBLE (-3252 2400);
FORCEADD TAP..1
(-3250 2300);
FORCEPROP 3 LASTPIN (-3300 2300) SIG_NAME M_J_CPU1_SA_CB<0>
J 0
(-3290 2310);
DISPLAY 0.659574 (-3290 2310);
PAINT MONO (-3290 2310);
DISPLAY INVISIBLE (-3290 2310);
FORCEPROP 1 LASTPIN (-3300 2300) BN 0
J 0
(-3312 2308);
DISPLAY 0.489362 (-3312 2308);
PAINT GREEN (-3312 2308);
FORCEPROP 2 LAST CDS_LIB mstr_standard
J 2
(-3250 2300);
DISPLAY 0.723404 (-3250 2300);
PAINT MONO (-3250 2300);
DISPLAY INVISIBLE (-3250 2300);
FORCEPROP 1 LAST BODY_TYPE PLUMBING
J 0
(-3250 2350);
DISPLAY 0.872340 (-3250 2350);
PAINT GREEN (-3250 2350);
DISPLAY INVISIBLE (-3250 2350);
FORCEPROP 1 LAST HDL_TAP TRUE
J 0
(-2925 2175);
DISPLAY 0.872340 (-2925 2175);
DISPLAY INVISIBLE (-2925 2175);
FORCEPROP 1 LAST PATH I227
J 0
(-3252 2300);
DISPLAY 0.872340 (-3252 2300);
PAINT GREEN (-3252 2300);
DISPLAY INVISIBLE (-3252 2300);
FORCEADD TAP..1
(-3250 2250);
FORCEPROP 3 LASTPIN (-3300 2250) SIG_NAME M_J_CPU1_SA_CB<1>
J 0
(-3290 2260);
DISPLAY 0.659574 (-3290 2260);
PAINT MONO (-3290 2260);
DISPLAY INVISIBLE (-3290 2260);
FORCEPROP 1 LASTPIN (-3300 2250) BN 1
J 0
(-3312 2258);
DISPLAY 0.489362 (-3312 2258);
PAINT GREEN (-3312 2258);
FORCEPROP 2 LAST CDS_LIB mstr_standard
J 2
(-3250 2250);
DISPLAY 0.723404 (-3250 2250);
PAINT MONO (-3250 2250);
DISPLAY INVISIBLE (-3250 2250);
FORCEPROP 1 LAST BODY_TYPE PLUMBING
J 0
(-3250 2300);
DISPLAY 0.872340 (-3250 2300);
PAINT GREEN (-3250 2300);
DISPLAY INVISIBLE (-3250 2300);
FORCEPROP 1 LAST HDL_TAP TRUE
J 0
(-2925 2125);
DISPLAY 0.872340 (-2925 2125);
DISPLAY INVISIBLE (-2925 2125);
FORCEPROP 1 LAST PATH I228
J 0
(-3252 2250);
DISPLAY 0.872340 (-3252 2250);
PAINT GREEN (-3252 2250);
DISPLAY INVISIBLE (-3252 2250);
FORCEADD TAP..1
(-3250 2200);
FORCEPROP 3 LASTPIN (-3300 2200) SIG_NAME M_J_CPU1_SA_CB<2>
J 0
(-3290 2210);
DISPLAY 0.659574 (-3290 2210);
PAINT MONO (-3290 2210);
DISPLAY INVISIBLE (-3290 2210);
FORCEPROP 1 LASTPIN (-3300 2200) BN 2
J 0
(-3312 2208);
DISPLAY 0.489362 (-3312 2208);
PAINT GREEN (-3312 2208);
FORCEPROP 2 LAST CDS_LIB mstr_standard
J 2
(-3250 2200);
DISPLAY 0.723404 (-3250 2200);
PAINT MONO (-3250 2200);
DISPLAY INVISIBLE (-3250 2200);
FORCEPROP 1 LAST BODY_TYPE PLUMBING
J 0
(-3250 2250);
DISPLAY 0.872340 (-3250 2250);
PAINT GREEN (-3250 2250);
DISPLAY INVISIBLE (-3250 2250);
FORCEPROP 1 LAST HDL_TAP TRUE
J 0
(-2925 2075);
DISPLAY 0.872340 (-2925 2075);
DISPLAY INVISIBLE (-2925 2075);
FORCEPROP 1 LAST PATH I229
J 0
(-3252 2200);
DISPLAY 0.872340 (-3252 2200);
PAINT GREEN (-3252 2200);
DISPLAY INVISIBLE (-3252 2200);
FORCEADD TAP..1
(-3250 2150);
FORCEPROP 3 LASTPIN (-3300 2150) SIG_NAME M_J_CPU1_SA_CB<3>
J 0
(-3290 2160);
DISPLAY 0.659574 (-3290 2160);
PAINT MONO (-3290 2160);
DISPLAY INVISIBLE (-3290 2160);
FORCEPROP 1 LASTPIN (-3300 2150) BN 3
J 0
(-3312 2158);
DISPLAY 0.489362 (-3312 2158);
PAINT GREEN (-3312 2158);
FORCEPROP 2 LAST CDS_LIB mstr_standard
J 2
(-3250 2150);
DISPLAY 0.723404 (-3250 2150);
PAINT MONO (-3250 2150);
DISPLAY INVISIBLE (-3250 2150);
FORCEPROP 1 LAST BODY_TYPE PLUMBING
J 0
(-3250 2200);
DISPLAY 0.872340 (-3250 2200);
PAINT GREEN (-3250 2200);
DISPLAY INVISIBLE (-3250 2200);
FORCEPROP 1 LAST HDL_TAP TRUE
J 0
(-2925 2025);
DISPLAY 0.872340 (-2925 2025);
DISPLAY INVISIBLE (-2925 2025);
FORCEPROP 1 LAST PATH I230
J 0
(-3252 2150);
DISPLAY 0.872340 (-3252 2150);
PAINT GREEN (-3252 2150);
DISPLAY INVISIBLE (-3252 2150);
FORCEADD TAP..1
(-3250 2100);
FORCEPROP 3 LASTPIN (-3300 2100) SIG_NAME M_J_CPU1_SA_CB<4>
J 0
(-3290 2110);
DISPLAY 0.659574 (-3290 2110);
PAINT MONO (-3290 2110);
DISPLAY INVISIBLE (-3290 2110);
FORCEPROP 1 LASTPIN (-3300 2100) BN 4
J 0
(-3312 2108);
DISPLAY 0.489362 (-3312 2108);
PAINT GREEN (-3312 2108);
FORCEPROP 2 LAST CDS_LIB mstr_standard
J 2
(-3250 2100);
DISPLAY 0.723404 (-3250 2100);
PAINT MONO (-3250 2100);
DISPLAY INVISIBLE (-3250 2100);
FORCEPROP 1 LAST BODY_TYPE PLUMBING
J 0
(-3250 2150);
DISPLAY 0.872340 (-3250 2150);
PAINT GREEN (-3250 2150);
DISPLAY INVISIBLE (-3250 2150);
FORCEPROP 1 LAST HDL_TAP TRUE
J 0
(-2925 1975);
DISPLAY 0.872340 (-2925 1975);
DISPLAY INVISIBLE (-2925 1975);
FORCEPROP 1 LAST PATH I231
J 0
(-3252 2100);
DISPLAY 0.872340 (-3252 2100);
PAINT GREEN (-3252 2100);
DISPLAY INVISIBLE (-3252 2100);
FORCEADD TAP..1
(-3250 2050);
FORCEPROP 3 LASTPIN (-3300 2050) SIG_NAME M_J_CPU1_SA_CB<5>
J 0
(-3290 2060);
DISPLAY 0.659574 (-3290 2060);
PAINT MONO (-3290 2060);
DISPLAY INVISIBLE (-3290 2060);
FORCEPROP 1 LASTPIN (-3300 2050) BN 5
J 0
(-3312 2058);
DISPLAY 0.489362 (-3312 2058);
PAINT GREEN (-3312 2058);
FORCEPROP 2 LAST CDS_LIB mstr_standard
J 2
(-3250 2050);
DISPLAY 0.723404 (-3250 2050);
PAINT MONO (-3250 2050);
DISPLAY INVISIBLE (-3250 2050);
FORCEPROP 1 LAST BODY_TYPE PLUMBING
J 0
(-3250 2100);
DISPLAY 0.872340 (-3250 2100);
PAINT GREEN (-3250 2100);
DISPLAY INVISIBLE (-3250 2100);
FORCEPROP 1 LAST HDL_TAP TRUE
J 0
(-2925 1925);
DISPLAY 0.872340 (-2925 1925);
DISPLAY INVISIBLE (-2925 1925);
FORCEPROP 1 LAST PATH I232
J 0
(-3252 2050);
DISPLAY 0.872340 (-3252 2050);
PAINT GREEN (-3252 2050);
DISPLAY INVISIBLE (-3252 2050);
FORCEADD OFFPAGE..6
R 2
(-2650 1900);
FORCEPROP 2 LAST $XR0 106 
J 0
(-2436 1900);
DISPLAY 0.638298 (-2436 1900);
PAINT MONO (-2436 1900);
FORCEPROP 2 LAST PATH I233
J 0
(-2425 1950);
DISPLAY 1.021277 (-2425 1950);
DISPLAY INVISIBLE (-2425 1950);
FORCEPROP 1 LAST COMMENT_BODY TRUE
J 2
(-2750 1825);
DISPLAY 0.872340 (-2750 1825);
PAINT GREEN (-2750 1825);
DISPLAY INVISIBLE (-2750 1825);
FORCEPROP 1 LAST OFFPAGE TRUE
J 2
(-2975 1775);
DISPLAY 0.872340 (-2975 1775);
PAINT GREEN (-2975 1775);
DISPLAY INVISIBLE (-2975 1775);
FORCEPROP 2 LAST CDS_LIB mstr_standard
J 2
(-2650 1900);
DISPLAY 0.723404 (-2650 1900);
PAINT MONO (-2650 1900);
DISPLAY INVISIBLE (-2650 1900);
FORCEADD TAP..1
(-3250 1950);
FORCEPROP 3 LASTPIN (-3300 1950) SIG_NAME M_J_CPU1_SA_CB<7>
J 0
(-3290 1960);
DISPLAY 0.659574 (-3290 1960);
PAINT MONO (-3290 1960);
DISPLAY INVISIBLE (-3290 1960);
FORCEPROP 1 LASTPIN (-3300 1950) BN 7
J 0
(-3312 1958);
DISPLAY 0.489362 (-3312 1958);
PAINT GREEN (-3312 1958);
FORCEPROP 2 LAST CDS_LIB mstr_standard
J 2
(-3250 1950);
DISPLAY 0.723404 (-3250 1950);
PAINT MONO (-3250 1950);
DISPLAY INVISIBLE (-3250 1950);
FORCEPROP 1 LAST BODY_TYPE PLUMBING
J 0
(-3250 2000);
DISPLAY 0.872340 (-3250 2000);
PAINT GREEN (-3250 2000);
DISPLAY INVISIBLE (-3250 2000);
FORCEPROP 1 LAST HDL_TAP TRUE
J 0
(-2925 1825);
DISPLAY 0.872340 (-2925 1825);
DISPLAY INVISIBLE (-2925 1825);
FORCEPROP 1 LAST PATH I234
J 0
(-3252 1950);
DISPLAY 0.872340 (-3252 1950);
PAINT GREEN (-3252 1950);
DISPLAY INVISIBLE (-3252 1950);
FORCEADD TAP..1
(-3250 2000);
FORCEPROP 3 LASTPIN (-3300 2000) SIG_NAME M_J_CPU1_SA_CB<6>
J 0
(-3290 2010);
DISPLAY 0.659574 (-3290 2010);
PAINT MONO (-3290 2010);
DISPLAY INVISIBLE (-3290 2010);
FORCEPROP 1 LASTPIN (-3300 2000) BN 6
J 0
(-3312 2008);
DISPLAY 0.489362 (-3312 2008);
PAINT GREEN (-3312 2008);
FORCEPROP 2 LAST CDS_LIB mstr_standard
J 2
(-3250 2000);
DISPLAY 0.723404 (-3250 2000);
PAINT MONO (-3250 2000);
DISPLAY INVISIBLE (-3250 2000);
FORCEPROP 1 LAST BODY_TYPE PLUMBING
J 0
(-3250 2050);
DISPLAY 0.872340 (-3250 2050);
PAINT GREEN (-3250 2050);
DISPLAY INVISIBLE (-3250 2050);
FORCEPROP 1 LAST HDL_TAP TRUE
J 0
(-2925 1875);
DISPLAY 0.872340 (-2925 1875);
DISPLAY INVISIBLE (-2925 1875);
FORCEPROP 1 LAST PATH I235
J 0
(-3252 2000);
DISPLAY 0.872340 (-3252 2000);
PAINT GREEN (-3252 2000);
DISPLAY INVISIBLE (-3252 2000);
FORCEADD TAP..1
(-3250 1800);
FORCEPROP 3 LASTPIN (-3300 1800) SIG_NAME M_J_CPU1_SB_CB<1>
J 0
(-3290 1810);
DISPLAY 0.659574 (-3290 1810);
PAINT MONO (-3290 1810);
DISPLAY INVISIBLE (-3290 1810);
FORCEPROP 1 LASTPIN (-3300 1800) BN 1
J 0
(-3312 1808);
DISPLAY 0.489362 (-3312 1808);
PAINT GREEN (-3312 1808);
FORCEPROP 2 LAST CDS_LIB mstr_standard
J 2
(-3250 1800);
DISPLAY 0.723404 (-3250 1800);
PAINT MONO (-3250 1800);
DISPLAY INVISIBLE (-3250 1800);
FORCEPROP 1 LAST BODY_TYPE PLUMBING
J 0
(-3250 1850);
DISPLAY 0.872340 (-3250 1850);
PAINT GREEN (-3250 1850);
DISPLAY INVISIBLE (-3250 1850);
FORCEPROP 1 LAST HDL_TAP TRUE
J 0
(-2925 1675);
DISPLAY 0.872340 (-2925 1675);
DISPLAY INVISIBLE (-2925 1675);
FORCEPROP 1 LAST PATH I236
J 0
(-3252 1800);
DISPLAY 0.872340 (-3252 1800);
PAINT GREEN (-3252 1800);
DISPLAY INVISIBLE (-3252 1800);
FORCEADD TAP..1
(-3250 1850);
FORCEPROP 3 LASTPIN (-3300 1850) SIG_NAME M_J_CPU1_SB_CB<0>
J 0
(-3290 1860);
DISPLAY 0.659574 (-3290 1860);
PAINT MONO (-3290 1860);
DISPLAY INVISIBLE (-3290 1860);
FORCEPROP 1 LASTPIN (-3300 1850) BN 0
J 0
(-3312 1858);
DISPLAY 0.489362 (-3312 1858);
PAINT GREEN (-3312 1858);
FORCEPROP 2 LAST CDS_LIB mstr_standard
J 2
(-3250 1850);
DISPLAY 0.723404 (-3250 1850);
PAINT MONO (-3250 1850);
DISPLAY INVISIBLE (-3250 1850);
FORCEPROP 1 LAST BODY_TYPE PLUMBING
J 0
(-3250 1900);
DISPLAY 0.872340 (-3250 1900);
PAINT GREEN (-3250 1900);
DISPLAY INVISIBLE (-3250 1900);
FORCEPROP 1 LAST HDL_TAP TRUE
J 0
(-2925 1725);
DISPLAY 0.872340 (-2925 1725);
DISPLAY INVISIBLE (-2925 1725);
FORCEPROP 1 LAST PATH I237
J 0
(-3252 1850);
DISPLAY 0.872340 (-3252 1850);
PAINT GREEN (-3252 1850);
DISPLAY INVISIBLE (-3252 1850);
FORCEADD TAP..1
(-3250 1700);
FORCEPROP 3 LASTPIN (-3300 1700) SIG_NAME M_J_CPU1_SB_CB<3>
J 0
(-3290 1710);
DISPLAY 0.659574 (-3290 1710);
PAINT MONO (-3290 1710);
DISPLAY INVISIBLE (-3290 1710);
FORCEPROP 1 LASTPIN (-3300 1700) BN 3
J 0
(-3312 1708);
DISPLAY 0.489362 (-3312 1708);
PAINT GREEN (-3312 1708);
FORCEPROP 2 LAST CDS_LIB mstr_standard
J 2
(-3250 1700);
DISPLAY 0.723404 (-3250 1700);
PAINT MONO (-3250 1700);
DISPLAY INVISIBLE (-3250 1700);
FORCEPROP 1 LAST BODY_TYPE PLUMBING
J 0
(-3250 1750);
DISPLAY 0.872340 (-3250 1750);
PAINT GREEN (-3250 1750);
DISPLAY INVISIBLE (-3250 1750);
FORCEPROP 1 LAST HDL_TAP TRUE
J 0
(-2925 1575);
DISPLAY 0.872340 (-2925 1575);
DISPLAY INVISIBLE (-2925 1575);
FORCEPROP 1 LAST PATH I238
J 0
(-3252 1700);
DISPLAY 0.872340 (-3252 1700);
PAINT GREEN (-3252 1700);
DISPLAY INVISIBLE (-3252 1700);
FORCEADD TAP..1
(-3250 1750);
FORCEPROP 3 LASTPIN (-3300 1750) SIG_NAME M_J_CPU1_SB_CB<2>
J 0
(-3290 1760);
DISPLAY 0.659574 (-3290 1760);
PAINT MONO (-3290 1760);
DISPLAY INVISIBLE (-3290 1760);
FORCEPROP 1 LASTPIN (-3300 1750) BN 2
J 0
(-3312 1758);
DISPLAY 0.489362 (-3312 1758);
PAINT GREEN (-3312 1758);
FORCEPROP 2 LAST CDS_LIB mstr_standard
J 2
(-3250 1750);
DISPLAY 0.723404 (-3250 1750);
PAINT MONO (-3250 1750);
DISPLAY INVISIBLE (-3250 1750);
FORCEPROP 1 LAST BODY_TYPE PLUMBING
J 0
(-3250 1800);
DISPLAY 0.872340 (-3250 1800);
PAINT GREEN (-3250 1800);
DISPLAY INVISIBLE (-3250 1800);
FORCEPROP 1 LAST HDL_TAP TRUE
J 0
(-2925 1625);
DISPLAY 0.872340 (-2925 1625);
DISPLAY INVISIBLE (-2925 1625);
FORCEPROP 1 LAST PATH I239
J 0
(-3252 1750);
DISPLAY 0.872340 (-3252 1750);
PAINT GREEN (-3252 1750);
DISPLAY INVISIBLE (-3252 1750);
FORCEADD TAP..1
(-3250 1650);
FORCEPROP 3 LASTPIN (-3300 1650) SIG_NAME M_J_CPU1_SB_CB<4>
J 0
(-3290 1660);
DISPLAY 0.659574 (-3290 1660);
PAINT MONO (-3290 1660);
DISPLAY INVISIBLE (-3290 1660);
FORCEPROP 1 LASTPIN (-3300 1650) BN 4
J 0
(-3312 1658);
DISPLAY 0.489362 (-3312 1658);
PAINT GREEN (-3312 1658);
FORCEPROP 2 LAST CDS_LIB mstr_standard
J 2
(-3250 1650);
DISPLAY 0.723404 (-3250 1650);
PAINT MONO (-3250 1650);
DISPLAY INVISIBLE (-3250 1650);
FORCEPROP 1 LAST BODY_TYPE PLUMBING
J 0
(-3250 1700);
DISPLAY 0.872340 (-3250 1700);
PAINT GREEN (-3250 1700);
DISPLAY INVISIBLE (-3250 1700);
FORCEPROP 1 LAST HDL_TAP TRUE
J 0
(-2925 1525);
DISPLAY 0.872340 (-2925 1525);
DISPLAY INVISIBLE (-2925 1525);
FORCEPROP 1 LAST PATH I240
J 0
(-3252 1650);
DISPLAY 0.872340 (-3252 1650);
PAINT GREEN (-3252 1650);
DISPLAY INVISIBLE (-3252 1650);
FORCEADD TAP..1
(-3250 1600);
FORCEPROP 3 LASTPIN (-3300 1600) SIG_NAME M_J_CPU1_SB_CB<5>
J 0
(-3290 1610);
DISPLAY 0.659574 (-3290 1610);
PAINT MONO (-3290 1610);
DISPLAY INVISIBLE (-3290 1610);
FORCEPROP 1 LASTPIN (-3300 1600) BN 5
J 0
(-3312 1608);
DISPLAY 0.489362 (-3312 1608);
PAINT GREEN (-3312 1608);
FORCEPROP 2 LAST CDS_LIB mstr_standard
J 2
(-3250 1600);
DISPLAY 0.723404 (-3250 1600);
PAINT MONO (-3250 1600);
DISPLAY INVISIBLE (-3250 1600);
FORCEPROP 1 LAST BODY_TYPE PLUMBING
J 0
(-3250 1650);
DISPLAY 0.872340 (-3250 1650);
PAINT GREEN (-3250 1650);
DISPLAY INVISIBLE (-3250 1650);
FORCEPROP 1 LAST HDL_TAP TRUE
J 0
(-2925 1475);
DISPLAY 0.872340 (-2925 1475);
DISPLAY INVISIBLE (-2925 1475);
FORCEPROP 1 LAST PATH I241
J 0
(-3252 1600);
DISPLAY 0.872340 (-3252 1600);
PAINT GREEN (-3252 1600);
DISPLAY INVISIBLE (-3252 1600);
FORCEADD TAP..1
(-3250 1550);
FORCEPROP 3 LASTPIN (-3300 1550) SIG_NAME M_J_CPU1_SB_CB<6>
J 0
(-3290 1560);
DISPLAY 0.659574 (-3290 1560);
PAINT MONO (-3290 1560);
DISPLAY INVISIBLE (-3290 1560);
FORCEPROP 1 LASTPIN (-3300 1550) BN 6
J 0
(-3312 1558);
DISPLAY 0.489362 (-3312 1558);
PAINT GREEN (-3312 1558);
FORCEPROP 2 LAST CDS_LIB mstr_standard
J 2
(-3250 1550);
DISPLAY 0.723404 (-3250 1550);
PAINT MONO (-3250 1550);
DISPLAY INVISIBLE (-3250 1550);
FORCEPROP 1 LAST BODY_TYPE PLUMBING
J 0
(-3250 1600);
DISPLAY 0.872340 (-3250 1600);
PAINT GREEN (-3250 1600);
DISPLAY INVISIBLE (-3250 1600);
FORCEPROP 1 LAST HDL_TAP TRUE
J 0
(-2925 1425);
DISPLAY 0.872340 (-2925 1425);
DISPLAY INVISIBLE (-2925 1425);
FORCEPROP 1 LAST PATH I242
J 0
(-3252 1550);
DISPLAY 0.872340 (-3252 1550);
PAINT GREEN (-3252 1550);
DISPLAY INVISIBLE (-3252 1550);
FORCEADD TAP..1
(-3250 1500);
FORCEPROP 3 LASTPIN (-3300 1500) SIG_NAME M_J_CPU1_SB_CB<7>
J 0
(-3290 1510);
DISPLAY 0.659574 (-3290 1510);
PAINT MONO (-3290 1510);
DISPLAY INVISIBLE (-3290 1510);
FORCEPROP 1 LASTPIN (-3300 1500) BN 7
J 0
(-3312 1508);
DISPLAY 0.489362 (-3312 1508);
PAINT GREEN (-3312 1508);
FORCEPROP 2 LAST CDS_LIB mstr_standard
J 2
(-3250 1500);
DISPLAY 0.723404 (-3250 1500);
PAINT MONO (-3250 1500);
DISPLAY INVISIBLE (-3250 1500);
FORCEPROP 1 LAST BODY_TYPE PLUMBING
J 0
(-3250 1550);
DISPLAY 0.872340 (-3250 1550);
PAINT GREEN (-3250 1550);
DISPLAY INVISIBLE (-3250 1550);
FORCEPROP 1 LAST HDL_TAP TRUE
J 0
(-2925 1375);
DISPLAY 0.872340 (-2925 1375);
DISPLAY INVISIBLE (-2925 1375);
FORCEPROP 1 LAST PATH I243
J 0
(-3252 1500);
DISPLAY 0.872340 (-3252 1500);
PAINT GREEN (-3252 1500);
DISPLAY INVISIBLE (-3252 1500);
FORCEADD TAP..1
R 2
(-5675 5900);
FORCEPROP 3 LASTPIN (-5625 5900) SIG_NAME M_J_CPU1_SA_DQS_DP<0>
J 0
(-5615 5910);
DISPLAY 0.659574 (-5615 5910);
PAINT MONO (-5615 5910);
DISPLAY INVISIBLE (-5615 5910);
FORCEPROP 1 LASTPIN (-5625 5900) BN 0
J 2
(-5613 5908);
DISPLAY 0.489362 (-5613 5908);
PAINT GREEN (-5613 5908);
FORCEPROP 2 LAST CDS_LIB mstr_standard
J 2
(-5675 5900);
DISPLAY 0.723404 (-5675 5900);
PAINT MONO (-5675 5900);
DISPLAY INVISIBLE (-5675 5900);
FORCEPROP 1 LAST BODY_TYPE PLUMBING
J 2
(-5675 5950);
DISPLAY 0.872340 (-5675 5950);
PAINT GREEN (-5675 5950);
DISPLAY INVISIBLE (-5675 5950);
FORCEPROP 1 LAST HDL_TAP TRUE
J 2
(-6000 5775);
DISPLAY 0.872340 (-6000 5775);
DISPLAY INVISIBLE (-6000 5775);
FORCEPROP 1 LAST PATH I244
J 2
(-5673 5900);
DISPLAY 0.872340 (-5673 5900);
PAINT GREEN (-5673 5900);
DISPLAY INVISIBLE (-5673 5900);
FORCEADD TAP..1
R 2
(-5675 5800);
FORCEPROP 3 LASTPIN (-5625 5800) SIG_NAME M_J_CPU1_SA_DQS_DP<1>
J 0
(-5615 5810);
DISPLAY 0.659574 (-5615 5810);
PAINT MONO (-5615 5810);
DISPLAY INVISIBLE (-5615 5810);
FORCEPROP 1 LASTPIN (-5625 5800) BN 1
J 2
(-5613 5808);
DISPLAY 0.489362 (-5613 5808);
PAINT GREEN (-5613 5808);
FORCEPROP 2 LAST CDS_LIB mstr_standard
J 2
(-5675 5800);
DISPLAY 0.723404 (-5675 5800);
PAINT MONO (-5675 5800);
DISPLAY INVISIBLE (-5675 5800);
FORCEPROP 1 LAST BODY_TYPE PLUMBING
J 2
(-5675 5850);
DISPLAY 0.872340 (-5675 5850);
PAINT GREEN (-5675 5850);
DISPLAY INVISIBLE (-5675 5850);
FORCEPROP 1 LAST HDL_TAP TRUE
J 2
(-6000 5675);
DISPLAY 0.872340 (-6000 5675);
DISPLAY INVISIBLE (-6000 5675);
FORCEPROP 1 LAST PATH I245
J 2
(-5673 5800);
DISPLAY 0.872340 (-5673 5800);
PAINT GREEN (-5673 5800);
DISPLAY INVISIBLE (-5673 5800);
FORCEADD TAP..1
R 2
(-5675 5700);
FORCEPROP 3 LASTPIN (-5625 5700) SIG_NAME M_J_CPU1_SA_DQS_DP<2>
J 0
(-5615 5710);
DISPLAY 0.659574 (-5615 5710);
PAINT MONO (-5615 5710);
DISPLAY INVISIBLE (-5615 5710);
FORCEPROP 1 LASTPIN (-5625 5700) BN 2
J 2
(-5613 5708);
DISPLAY 0.489362 (-5613 5708);
PAINT GREEN (-5613 5708);
FORCEPROP 2 LAST CDS_LIB mstr_standard
J 2
(-5675 5700);
DISPLAY 0.723404 (-5675 5700);
PAINT MONO (-5675 5700);
DISPLAY INVISIBLE (-5675 5700);
FORCEPROP 1 LAST BODY_TYPE PLUMBING
J 2
(-5675 5750);
DISPLAY 0.872340 (-5675 5750);
PAINT GREEN (-5675 5750);
DISPLAY INVISIBLE (-5675 5750);
FORCEPROP 1 LAST HDL_TAP TRUE
J 2
(-6000 5575);
DISPLAY 0.872340 (-6000 5575);
DISPLAY INVISIBLE (-6000 5575);
FORCEPROP 1 LAST PATH I246
J 2
(-5673 5700);
DISPLAY 0.872340 (-5673 5700);
PAINT GREEN (-5673 5700);
DISPLAY INVISIBLE (-5673 5700);
FORCEADD TAP..1
R 2
(-5675 5600);
FORCEPROP 3 LASTPIN (-5625 5600) SIG_NAME M_J_CPU1_SA_DQS_DP<3>
J 0
(-5615 5610);
DISPLAY 0.659574 (-5615 5610);
PAINT MONO (-5615 5610);
DISPLAY INVISIBLE (-5615 5610);
FORCEPROP 1 LASTPIN (-5625 5600) BN 3
J 2
(-5613 5608);
DISPLAY 0.489362 (-5613 5608);
PAINT GREEN (-5613 5608);
FORCEPROP 2 LAST CDS_LIB mstr_standard
J 2
(-5675 5600);
DISPLAY 0.723404 (-5675 5600);
PAINT MONO (-5675 5600);
DISPLAY INVISIBLE (-5675 5600);
FORCEPROP 1 LAST BODY_TYPE PLUMBING
J 2
(-5675 5650);
DISPLAY 0.872340 (-5675 5650);
PAINT GREEN (-5675 5650);
DISPLAY INVISIBLE (-5675 5650);
FORCEPROP 1 LAST HDL_TAP TRUE
J 2
(-6000 5475);
DISPLAY 0.872340 (-6000 5475);
DISPLAY INVISIBLE (-6000 5475);
FORCEPROP 1 LAST PATH I247
J 2
(-5673 5600);
DISPLAY 0.872340 (-5673 5600);
PAINT GREEN (-5673 5600);
DISPLAY INVISIBLE (-5673 5600);
FORCEADD TAP..1
R 2
(-5675 5500);
FORCEPROP 3 LASTPIN (-5625 5500) SIG_NAME M_J_CPU1_SA_DQS_DP<4>
J 0
(-5615 5510);
DISPLAY 0.659574 (-5615 5510);
PAINT MONO (-5615 5510);
DISPLAY INVISIBLE (-5615 5510);
FORCEPROP 1 LASTPIN (-5625 5500) BN 4
J 2
(-5613 5508);
DISPLAY 0.489362 (-5613 5508);
PAINT GREEN (-5613 5508);
FORCEPROP 2 LAST CDS_LIB mstr_standard
J 2
(-5675 5500);
DISPLAY 0.723404 (-5675 5500);
PAINT MONO (-5675 5500);
DISPLAY INVISIBLE (-5675 5500);
FORCEPROP 1 LAST BODY_TYPE PLUMBING
J 2
(-5675 5550);
DISPLAY 0.872340 (-5675 5550);
PAINT GREEN (-5675 5550);
DISPLAY INVISIBLE (-5675 5550);
FORCEPROP 1 LAST HDL_TAP TRUE
J 2
(-6000 5375);
DISPLAY 0.872340 (-6000 5375);
DISPLAY INVISIBLE (-6000 5375);
FORCEPROP 1 LAST PATH I248
J 2
(-5673 5500);
DISPLAY 0.872340 (-5673 5500);
PAINT GREEN (-5673 5500);
DISPLAY INVISIBLE (-5673 5500);
FORCEADD TAP..1
R 2
(-5675 5400);
FORCEPROP 3 LASTPIN (-5625 5400) SIG_NAME M_J_CPU1_SA_DQS_DP<5>
J 0
(-5615 5410);
DISPLAY 0.659574 (-5615 5410);
PAINT MONO (-5615 5410);
DISPLAY INVISIBLE (-5615 5410);
FORCEPROP 1 LASTPIN (-5625 5400) BN 5
J 2
(-5613 5408);
DISPLAY 0.489362 (-5613 5408);
PAINT GREEN (-5613 5408);
FORCEPROP 2 LAST CDS_LIB mstr_standard
J 2
(-5675 5400);
DISPLAY 0.723404 (-5675 5400);
PAINT MONO (-5675 5400);
DISPLAY INVISIBLE (-5675 5400);
FORCEPROP 1 LAST BODY_TYPE PLUMBING
J 2
(-5675 5450);
DISPLAY 0.872340 (-5675 5450);
PAINT GREEN (-5675 5450);
DISPLAY INVISIBLE (-5675 5450);
FORCEPROP 1 LAST HDL_TAP TRUE
J 2
(-6000 5275);
DISPLAY 0.872340 (-6000 5275);
DISPLAY INVISIBLE (-6000 5275);
FORCEPROP 1 LAST PATH I249
J 2
(-5673 5400);
DISPLAY 0.872340 (-5673 5400);
PAINT GREEN (-5673 5400);
DISPLAY INVISIBLE (-5673 5400);
FORCEADD TAP..1
R 2
(-5675 5300);
FORCEPROP 3 LASTPIN (-5625 5300) SIG_NAME M_J_CPU1_SA_DQS_DP<6>
J 0
(-5615 5310);
DISPLAY 0.659574 (-5615 5310);
PAINT MONO (-5615 5310);
DISPLAY INVISIBLE (-5615 5310);
FORCEPROP 1 LASTPIN (-5625 5300) BN 6
J 2
(-5613 5308);
DISPLAY 0.489362 (-5613 5308);
PAINT GREEN (-5613 5308);
FORCEPROP 2 LAST CDS_LIB mstr_standard
J 2
(-5675 5300);
DISPLAY 0.723404 (-5675 5300);
PAINT MONO (-5675 5300);
DISPLAY INVISIBLE (-5675 5300);
FORCEPROP 1 LAST BODY_TYPE PLUMBING
J 2
(-5675 5350);
DISPLAY 0.872340 (-5675 5350);
PAINT GREEN (-5675 5350);
DISPLAY INVISIBLE (-5675 5350);
FORCEPROP 1 LAST HDL_TAP TRUE
J 2
(-6000 5175);
DISPLAY 0.872340 (-6000 5175);
DISPLAY INVISIBLE (-6000 5175);
FORCEPROP 1 LAST PATH I250
J 2
(-5673 5300);
DISPLAY 0.872340 (-5673 5300);
PAINT GREEN (-5673 5300);
DISPLAY INVISIBLE (-5673 5300);
FORCEADD TAP..1
R 2
(-5675 5200);
FORCEPROP 3 LASTPIN (-5625 5200) SIG_NAME M_J_CPU1_SA_DQS_DP<7>
J 0
(-5615 5210);
DISPLAY 0.659574 (-5615 5210);
PAINT MONO (-5615 5210);
DISPLAY INVISIBLE (-5615 5210);
FORCEPROP 1 LASTPIN (-5625 5200) BN 7
J 2
(-5613 5208);
DISPLAY 0.489362 (-5613 5208);
PAINT GREEN (-5613 5208);
FORCEPROP 2 LAST CDS_LIB mstr_standard
J 2
(-5675 5200);
DISPLAY 0.723404 (-5675 5200);
PAINT MONO (-5675 5200);
DISPLAY INVISIBLE (-5675 5200);
FORCEPROP 1 LAST BODY_TYPE PLUMBING
J 2
(-5675 5250);
DISPLAY 0.872340 (-5675 5250);
PAINT GREEN (-5675 5250);
DISPLAY INVISIBLE (-5675 5250);
FORCEPROP 1 LAST HDL_TAP TRUE
J 2
(-6000 5075);
DISPLAY 0.872340 (-6000 5075);
DISPLAY INVISIBLE (-6000 5075);
FORCEPROP 1 LAST PATH I251
J 2
(-5673 5200);
DISPLAY 0.872340 (-5673 5200);
PAINT GREEN (-5673 5200);
DISPLAY INVISIBLE (-5673 5200);
FORCEADD TAP..1
R 2
(-5875 5850);
FORCEPROP 3 LASTPIN (-5825 5850) SIG_NAME M_J_CPU1_SA_DQS_DN<0>
J 0
(-5815 5860);
DISPLAY 0.659574 (-5815 5860);
PAINT MONO (-5815 5860);
DISPLAY INVISIBLE (-5815 5860);
FORCEPROP 1 LASTPIN (-5825 5850) BN 0
J 2
(-5813 5858);
DISPLAY 0.489362 (-5813 5858);
PAINT GREEN (-5813 5858);
FORCEPROP 2 LAST CDS_LIB mstr_standard
J 2
(-5875 5850);
DISPLAY 0.723404 (-5875 5850);
PAINT MONO (-5875 5850);
DISPLAY INVISIBLE (-5875 5850);
FORCEPROP 1 LAST BODY_TYPE PLUMBING
J 2
(-5875 5900);
DISPLAY 0.872340 (-5875 5900);
PAINT GREEN (-5875 5900);
DISPLAY INVISIBLE (-5875 5900);
FORCEPROP 1 LAST HDL_TAP TRUE
J 2
(-6200 5725);
DISPLAY 0.872340 (-6200 5725);
DISPLAY INVISIBLE (-6200 5725);
FORCEPROP 1 LAST PATH I252
J 2
(-5873 5850);
DISPLAY 0.872340 (-5873 5850);
PAINT GREEN (-5873 5850);
DISPLAY INVISIBLE (-5873 5850);
FORCEADD TAP..1
R 2
(-5875 5650);
FORCEPROP 3 LASTPIN (-5825 5650) SIG_NAME M_J_CPU1_SA_DQS_DN<2>
J 0
(-5815 5660);
DISPLAY 0.659574 (-5815 5660);
PAINT MONO (-5815 5660);
DISPLAY INVISIBLE (-5815 5660);
FORCEPROP 1 LASTPIN (-5825 5650) BN 2
J 2
(-5813 5658);
DISPLAY 0.489362 (-5813 5658);
PAINT GREEN (-5813 5658);
FORCEPROP 2 LAST CDS_LIB mstr_standard
J 2
(-5875 5650);
DISPLAY 0.723404 (-5875 5650);
PAINT MONO (-5875 5650);
DISPLAY INVISIBLE (-5875 5650);
FORCEPROP 1 LAST BODY_TYPE PLUMBING
J 2
(-5875 5700);
DISPLAY 0.872340 (-5875 5700);
PAINT GREEN (-5875 5700);
DISPLAY INVISIBLE (-5875 5700);
FORCEPROP 1 LAST HDL_TAP TRUE
J 2
(-6200 5525);
DISPLAY 0.872340 (-6200 5525);
DISPLAY INVISIBLE (-6200 5525);
FORCEPROP 1 LAST PATH I253
J 2
(-5873 5650);
DISPLAY 0.872340 (-5873 5650);
PAINT GREEN (-5873 5650);
DISPLAY INVISIBLE (-5873 5650);
FORCEADD TAP..1
R 2
(-5875 5750);
FORCEPROP 3 LASTPIN (-5825 5750) SIG_NAME M_J_CPU1_SA_DQS_DN<1>
J 0
(-5815 5760);
DISPLAY 0.659574 (-5815 5760);
PAINT MONO (-5815 5760);
DISPLAY INVISIBLE (-5815 5760);
FORCEPROP 1 LASTPIN (-5825 5750) BN 1
J 2
(-5813 5758);
DISPLAY 0.489362 (-5813 5758);
PAINT GREEN (-5813 5758);
FORCEPROP 2 LAST CDS_LIB mstr_standard
J 2
(-5875 5750);
DISPLAY 0.723404 (-5875 5750);
PAINT MONO (-5875 5750);
DISPLAY INVISIBLE (-5875 5750);
FORCEPROP 1 LAST BODY_TYPE PLUMBING
J 2
(-5875 5800);
DISPLAY 0.872340 (-5875 5800);
PAINT GREEN (-5875 5800);
DISPLAY INVISIBLE (-5875 5800);
FORCEPROP 1 LAST HDL_TAP TRUE
J 2
(-6200 5625);
DISPLAY 0.872340 (-6200 5625);
DISPLAY INVISIBLE (-6200 5625);
FORCEPROP 1 LAST PATH I254
J 2
(-5873 5750);
DISPLAY 0.872340 (-5873 5750);
PAINT GREEN (-5873 5750);
DISPLAY INVISIBLE (-5873 5750);
FORCEADD TAP..1
R 2
(-5875 5550);
FORCEPROP 3 LASTPIN (-5825 5550) SIG_NAME M_J_CPU1_SA_DQS_DN<3>
J 0
(-5815 5560);
DISPLAY 0.659574 (-5815 5560);
PAINT MONO (-5815 5560);
DISPLAY INVISIBLE (-5815 5560);
FORCEPROP 1 LASTPIN (-5825 5550) BN 3
J 2
(-5813 5558);
DISPLAY 0.489362 (-5813 5558);
PAINT GREEN (-5813 5558);
FORCEPROP 2 LAST CDS_LIB mstr_standard
J 2
(-5875 5550);
DISPLAY 0.723404 (-5875 5550);
PAINT MONO (-5875 5550);
DISPLAY INVISIBLE (-5875 5550);
FORCEPROP 1 LAST BODY_TYPE PLUMBING
J 2
(-5875 5600);
DISPLAY 0.872340 (-5875 5600);
PAINT GREEN (-5875 5600);
DISPLAY INVISIBLE (-5875 5600);
FORCEPROP 1 LAST HDL_TAP TRUE
J 2
(-6200 5425);
DISPLAY 0.872340 (-6200 5425);
DISPLAY INVISIBLE (-6200 5425);
FORCEPROP 1 LAST PATH I255
J 2
(-5873 5550);
DISPLAY 0.872340 (-5873 5550);
PAINT GREEN (-5873 5550);
DISPLAY INVISIBLE (-5873 5550);
FORCEADD TAP..1
R 2
(-5875 5450);
FORCEPROP 3 LASTPIN (-5825 5450) SIG_NAME M_J_CPU1_SA_DQS_DN<4>
J 0
(-5815 5460);
DISPLAY 0.659574 (-5815 5460);
PAINT MONO (-5815 5460);
DISPLAY INVISIBLE (-5815 5460);
FORCEPROP 1 LASTPIN (-5825 5450) BN 4
J 2
(-5813 5458);
DISPLAY 0.489362 (-5813 5458);
PAINT GREEN (-5813 5458);
FORCEPROP 2 LAST CDS_LIB mstr_standard
J 2
(-5875 5450);
DISPLAY 0.723404 (-5875 5450);
PAINT MONO (-5875 5450);
DISPLAY INVISIBLE (-5875 5450);
FORCEPROP 1 LAST BODY_TYPE PLUMBING
J 2
(-5875 5500);
DISPLAY 0.872340 (-5875 5500);
PAINT GREEN (-5875 5500);
DISPLAY INVISIBLE (-5875 5500);
FORCEPROP 1 LAST HDL_TAP TRUE
J 2
(-6200 5325);
DISPLAY 0.872340 (-6200 5325);
DISPLAY INVISIBLE (-6200 5325);
FORCEPROP 1 LAST PATH I256
J 2
(-5873 5450);
DISPLAY 0.872340 (-5873 5450);
PAINT GREEN (-5873 5450);
DISPLAY INVISIBLE (-5873 5450);
FORCEADD TAP..1
R 2
(-5875 5250);
FORCEPROP 3 LASTPIN (-5825 5250) SIG_NAME M_J_CPU1_SA_DQS_DN<6>
J 0
(-5815 5260);
DISPLAY 0.659574 (-5815 5260);
PAINT MONO (-5815 5260);
DISPLAY INVISIBLE (-5815 5260);
FORCEPROP 1 LASTPIN (-5825 5250) BN 6
J 2
(-5813 5258);
DISPLAY 0.489362 (-5813 5258);
PAINT GREEN (-5813 5258);
FORCEPROP 2 LAST CDS_LIB mstr_standard
J 2
(-5875 5250);
DISPLAY 0.723404 (-5875 5250);
PAINT MONO (-5875 5250);
DISPLAY INVISIBLE (-5875 5250);
FORCEPROP 1 LAST BODY_TYPE PLUMBING
J 2
(-5875 5300);
DISPLAY 0.872340 (-5875 5300);
PAINT GREEN (-5875 5300);
DISPLAY INVISIBLE (-5875 5300);
FORCEPROP 1 LAST HDL_TAP TRUE
J 2
(-6200 5125);
DISPLAY 0.872340 (-6200 5125);
DISPLAY INVISIBLE (-6200 5125);
FORCEPROP 1 LAST PATH I257
J 2
(-5873 5250);
DISPLAY 0.872340 (-5873 5250);
PAINT GREEN (-5873 5250);
DISPLAY INVISIBLE (-5873 5250);
FORCEADD TAP..1
R 2
(-5875 5350);
FORCEPROP 3 LASTPIN (-5825 5350) SIG_NAME M_J_CPU1_SA_DQS_DN<5>
J 0
(-5815 5360);
DISPLAY 0.659574 (-5815 5360);
PAINT MONO (-5815 5360);
DISPLAY INVISIBLE (-5815 5360);
FORCEPROP 1 LASTPIN (-5825 5350) BN 5
J 2
(-5813 5358);
DISPLAY 0.489362 (-5813 5358);
PAINT GREEN (-5813 5358);
FORCEPROP 2 LAST CDS_LIB mstr_standard
J 2
(-5875 5350);
DISPLAY 0.723404 (-5875 5350);
PAINT MONO (-5875 5350);
DISPLAY INVISIBLE (-5875 5350);
FORCEPROP 1 LAST BODY_TYPE PLUMBING
J 2
(-5875 5400);
DISPLAY 0.872340 (-5875 5400);
PAINT GREEN (-5875 5400);
DISPLAY INVISIBLE (-5875 5400);
FORCEPROP 1 LAST HDL_TAP TRUE
J 2
(-6200 5225);
DISPLAY 0.872340 (-6200 5225);
DISPLAY INVISIBLE (-6200 5225);
FORCEPROP 1 LAST PATH I258
J 2
(-5873 5350);
DISPLAY 0.872340 (-5873 5350);
PAINT GREEN (-5873 5350);
DISPLAY INVISIBLE (-5873 5350);
FORCEADD TAP..1
R 2
(-5875 5150);
FORCEPROP 3 LASTPIN (-5825 5150) SIG_NAME M_J_CPU1_SA_DQS_DN<7>
J 0
(-5815 5160);
DISPLAY 0.659574 (-5815 5160);
PAINT MONO (-5815 5160);
DISPLAY INVISIBLE (-5815 5160);
FORCEPROP 1 LASTPIN (-5825 5150) BN 7
J 2
(-5813 5158);
DISPLAY 0.489362 (-5813 5158);
PAINT GREEN (-5813 5158);
FORCEPROP 2 LAST CDS_LIB mstr_standard
J 2
(-5875 5150);
DISPLAY 0.723404 (-5875 5150);
PAINT MONO (-5875 5150);
DISPLAY INVISIBLE (-5875 5150);
FORCEPROP 1 LAST BODY_TYPE PLUMBING
J 2
(-5875 5200);
DISPLAY 0.872340 (-5875 5200);
PAINT GREEN (-5875 5200);
DISPLAY INVISIBLE (-5875 5200);
FORCEPROP 1 LAST HDL_TAP TRUE
J 2
(-6200 5025);
DISPLAY 0.872340 (-6200 5025);
DISPLAY INVISIBLE (-6200 5025);
FORCEPROP 1 LAST PATH I259
J 2
(-5873 5150);
DISPLAY 0.872340 (-5873 5150);
PAINT GREEN (-5873 5150);
DISPLAY INVISIBLE (-5873 5150);
FORCEADD TAP..1
R 2
(-5675 5000);
FORCEPROP 3 LASTPIN (-5625 5000) SIG_NAME M_J_CPU1_SA_DQS_DP<9>
J 0
(-5615 5010);
DISPLAY 0.659574 (-5615 5010);
PAINT MONO (-5615 5010);
DISPLAY INVISIBLE (-5615 5010);
FORCEPROP 1 LASTPIN (-5625 5000) BN 9
J 2
(-5613 5008);
DISPLAY 0.489362 (-5613 5008);
PAINT GREEN (-5613 5008);
FORCEPROP 2 LAST CDS_LIB mstr_standard
J 2
(-5675 5000);
DISPLAY 0.723404 (-5675 5000);
PAINT MONO (-5675 5000);
DISPLAY INVISIBLE (-5675 5000);
FORCEPROP 1 LAST BODY_TYPE PLUMBING
J 2
(-5675 5050);
DISPLAY 0.872340 (-5675 5050);
PAINT GREEN (-5675 5050);
DISPLAY INVISIBLE (-5675 5050);
FORCEPROP 1 LAST HDL_TAP TRUE
J 2
(-6000 4875);
DISPLAY 0.872340 (-6000 4875);
DISPLAY INVISIBLE (-6000 4875);
FORCEPROP 1 LAST PATH I260
J 2
(-5673 5000);
DISPLAY 0.872340 (-5673 5000);
PAINT GREEN (-5673 5000);
DISPLAY INVISIBLE (-5673 5000);
FORCEADD TAP..1
R 2
(-5675 5100);
FORCEPROP 3 LASTPIN (-5625 5100) SIG_NAME M_J_CPU1_SA_DQS_DP<8>
J 0
(-5615 5110);
DISPLAY 0.659574 (-5615 5110);
PAINT MONO (-5615 5110);
DISPLAY INVISIBLE (-5615 5110);
FORCEPROP 1 LASTPIN (-5625 5100) BN 8
J 2
(-5613 5108);
DISPLAY 0.489362 (-5613 5108);
PAINT GREEN (-5613 5108);
FORCEPROP 2 LAST CDS_LIB mstr_standard
J 2
(-5675 5100);
DISPLAY 0.723404 (-5675 5100);
PAINT MONO (-5675 5100);
DISPLAY INVISIBLE (-5675 5100);
FORCEPROP 1 LAST BODY_TYPE PLUMBING
J 2
(-5675 5150);
DISPLAY 0.872340 (-5675 5150);
PAINT GREEN (-5675 5150);
DISPLAY INVISIBLE (-5675 5150);
FORCEPROP 1 LAST HDL_TAP TRUE
J 2
(-6000 4975);
DISPLAY 0.872340 (-6000 4975);
DISPLAY INVISIBLE (-6000 4975);
FORCEPROP 1 LAST PATH I261
J 2
(-5673 5100);
DISPLAY 0.872340 (-5673 5100);
PAINT GREEN (-5673 5100);
DISPLAY INVISIBLE (-5673 5100);
FORCEADD TAP..1
R 2
(-5675 4850);
FORCEPROP 3 LASTPIN (-5625 4850) SIG_NAME M_J_CPU1_SB_DQS_DP<0>
J 0
(-5615 4860);
DISPLAY 0.659574 (-5615 4860);
PAINT MONO (-5615 4860);
DISPLAY INVISIBLE (-5615 4860);
FORCEPROP 1 LASTPIN (-5625 4850) BN 0
J 2
(-5613 4858);
DISPLAY 0.489362 (-5613 4858);
PAINT GREEN (-5613 4858);
FORCEPROP 2 LAST CDS_LIB mstr_standard
J 2
(-5675 4850);
DISPLAY 0.723404 (-5675 4850);
PAINT MONO (-5675 4850);
DISPLAY INVISIBLE (-5675 4850);
FORCEPROP 1 LAST BODY_TYPE PLUMBING
J 2
(-5675 4900);
DISPLAY 0.872340 (-5675 4900);
PAINT GREEN (-5675 4900);
DISPLAY INVISIBLE (-5675 4900);
FORCEPROP 1 LAST HDL_TAP TRUE
J 2
(-6000 4725);
DISPLAY 0.872340 (-6000 4725);
DISPLAY INVISIBLE (-6000 4725);
FORCEPROP 1 LAST PATH I262
J 2
(-5673 4850);
DISPLAY 0.872340 (-5673 4850);
PAINT GREEN (-5673 4850);
DISPLAY INVISIBLE (-5673 4850);
FORCEADD TAP..1
R 2
(-5675 4750);
FORCEPROP 3 LASTPIN (-5625 4750) SIG_NAME M_J_CPU1_SB_DQS_DP<1>
J 0
(-5615 4760);
DISPLAY 0.659574 (-5615 4760);
PAINT MONO (-5615 4760);
DISPLAY INVISIBLE (-5615 4760);
FORCEPROP 1 LASTPIN (-5625 4750) BN 1
J 2
(-5613 4758);
DISPLAY 0.489362 (-5613 4758);
PAINT GREEN (-5613 4758);
FORCEPROP 2 LAST CDS_LIB mstr_standard
J 2
(-5675 4750);
DISPLAY 0.723404 (-5675 4750);
PAINT MONO (-5675 4750);
DISPLAY INVISIBLE (-5675 4750);
FORCEPROP 1 LAST BODY_TYPE PLUMBING
J 2
(-5675 4800);
DISPLAY 0.872340 (-5675 4800);
PAINT GREEN (-5675 4800);
DISPLAY INVISIBLE (-5675 4800);
FORCEPROP 1 LAST HDL_TAP TRUE
J 2
(-6000 4625);
DISPLAY 0.872340 (-6000 4625);
DISPLAY INVISIBLE (-6000 4625);
FORCEPROP 1 LAST PATH I263
J 2
(-5673 4750);
DISPLAY 0.872340 (-5673 4750);
PAINT GREEN (-5673 4750);
DISPLAY INVISIBLE (-5673 4750);
FORCEADD TAP..1
R 2
(-5675 4650);
FORCEPROP 3 LASTPIN (-5625 4650) SIG_NAME M_J_CPU1_SB_DQS_DP<2>
J 0
(-5615 4660);
DISPLAY 0.659574 (-5615 4660);
PAINT MONO (-5615 4660);
DISPLAY INVISIBLE (-5615 4660);
FORCEPROP 1 LASTPIN (-5625 4650) BN 2
J 2
(-5613 4658);
DISPLAY 0.489362 (-5613 4658);
PAINT GREEN (-5613 4658);
FORCEPROP 2 LAST CDS_LIB mstr_standard
J 2
(-5675 4650);
DISPLAY 0.723404 (-5675 4650);
PAINT MONO (-5675 4650);
DISPLAY INVISIBLE (-5675 4650);
FORCEPROP 1 LAST BODY_TYPE PLUMBING
J 2
(-5675 4700);
DISPLAY 0.872340 (-5675 4700);
PAINT GREEN (-5675 4700);
DISPLAY INVISIBLE (-5675 4700);
FORCEPROP 1 LAST HDL_TAP TRUE
J 2
(-6000 4525);
DISPLAY 0.872340 (-6000 4525);
DISPLAY INVISIBLE (-6000 4525);
FORCEPROP 1 LAST PATH I264
J 2
(-5673 4650);
DISPLAY 0.872340 (-5673 4650);
PAINT GREEN (-5673 4650);
DISPLAY INVISIBLE (-5673 4650);
FORCEADD TAP..1
R 2
(-5675 4550);
FORCEPROP 3 LASTPIN (-5625 4550) SIG_NAME M_J_CPU1_SB_DQS_DP<3>
J 0
(-5615 4560);
DISPLAY 0.659574 (-5615 4560);
PAINT MONO (-5615 4560);
DISPLAY INVISIBLE (-5615 4560);
FORCEPROP 1 LASTPIN (-5625 4550) BN 3
J 2
(-5613 4558);
DISPLAY 0.489362 (-5613 4558);
PAINT GREEN (-5613 4558);
FORCEPROP 2 LAST CDS_LIB mstr_standard
J 2
(-5675 4550);
DISPLAY 0.723404 (-5675 4550);
PAINT MONO (-5675 4550);
DISPLAY INVISIBLE (-5675 4550);
FORCEPROP 1 LAST BODY_TYPE PLUMBING
J 2
(-5675 4600);
DISPLAY 0.872340 (-5675 4600);
PAINT GREEN (-5675 4600);
DISPLAY INVISIBLE (-5675 4600);
FORCEPROP 1 LAST HDL_TAP TRUE
J 2
(-6000 4425);
DISPLAY 0.872340 (-6000 4425);
DISPLAY INVISIBLE (-6000 4425);
FORCEPROP 1 LAST PATH I265
J 2
(-5673 4550);
DISPLAY 0.872340 (-5673 4550);
PAINT GREEN (-5673 4550);
DISPLAY INVISIBLE (-5673 4550);
FORCEADD TAP..1
R 2
(-5675 4450);
FORCEPROP 3 LASTPIN (-5625 4450) SIG_NAME M_J_CPU1_SB_DQS_DP<4>
J 0
(-5615 4460);
DISPLAY 0.659574 (-5615 4460);
PAINT MONO (-5615 4460);
DISPLAY INVISIBLE (-5615 4460);
FORCEPROP 1 LASTPIN (-5625 4450) BN 4
J 2
(-5613 4458);
DISPLAY 0.489362 (-5613 4458);
PAINT GREEN (-5613 4458);
FORCEPROP 2 LAST CDS_LIB mstr_standard
J 2
(-5675 4450);
DISPLAY 0.723404 (-5675 4450);
PAINT MONO (-5675 4450);
DISPLAY INVISIBLE (-5675 4450);
FORCEPROP 1 LAST BODY_TYPE PLUMBING
J 2
(-5675 4500);
DISPLAY 0.872340 (-5675 4500);
PAINT GREEN (-5675 4500);
DISPLAY INVISIBLE (-5675 4500);
FORCEPROP 1 LAST HDL_TAP TRUE
J 2
(-6000 4325);
DISPLAY 0.872340 (-6000 4325);
DISPLAY INVISIBLE (-6000 4325);
FORCEPROP 1 LAST PATH I266
J 2
(-5673 4450);
DISPLAY 0.872340 (-5673 4450);
PAINT GREEN (-5673 4450);
DISPLAY INVISIBLE (-5673 4450);
FORCEADD TAP..1
R 2
(-5675 4350);
FORCEPROP 3 LASTPIN (-5625 4350) SIG_NAME M_J_CPU1_SB_DQS_DP<5>
J 0
(-5615 4360);
DISPLAY 0.659574 (-5615 4360);
PAINT MONO (-5615 4360);
DISPLAY INVISIBLE (-5615 4360);
FORCEPROP 1 LASTPIN (-5625 4350) BN 5
J 2
(-5613 4358);
DISPLAY 0.489362 (-5613 4358);
PAINT GREEN (-5613 4358);
FORCEPROP 2 LAST CDS_LIB mstr_standard
J 2
(-5675 4350);
DISPLAY 0.723404 (-5675 4350);
PAINT MONO (-5675 4350);
DISPLAY INVISIBLE (-5675 4350);
FORCEPROP 1 LAST BODY_TYPE PLUMBING
J 2
(-5675 4400);
DISPLAY 0.872340 (-5675 4400);
PAINT GREEN (-5675 4400);
DISPLAY INVISIBLE (-5675 4400);
FORCEPROP 1 LAST HDL_TAP TRUE
J 2
(-6000 4225);
DISPLAY 0.872340 (-6000 4225);
DISPLAY INVISIBLE (-6000 4225);
FORCEPROP 1 LAST PATH I267
J 2
(-5673 4350);
DISPLAY 0.872340 (-5673 4350);
PAINT GREEN (-5673 4350);
DISPLAY INVISIBLE (-5673 4350);
FORCEADD TAP..1
R 2
(-5675 4250);
FORCEPROP 3 LASTPIN (-5625 4250) SIG_NAME M_J_CPU1_SB_DQS_DP<6>
J 0
(-5615 4260);
DISPLAY 0.659574 (-5615 4260);
PAINT MONO (-5615 4260);
DISPLAY INVISIBLE (-5615 4260);
FORCEPROP 1 LASTPIN (-5625 4250) BN 6
J 2
(-5613 4258);
DISPLAY 0.489362 (-5613 4258);
PAINT GREEN (-5613 4258);
FORCEPROP 2 LAST CDS_LIB mstr_standard
J 2
(-5675 4250);
DISPLAY 0.723404 (-5675 4250);
PAINT MONO (-5675 4250);
DISPLAY INVISIBLE (-5675 4250);
FORCEPROP 1 LAST BODY_TYPE PLUMBING
J 2
(-5675 4300);
DISPLAY 0.872340 (-5675 4300);
PAINT GREEN (-5675 4300);
DISPLAY INVISIBLE (-5675 4300);
FORCEPROP 1 LAST HDL_TAP TRUE
J 2
(-6000 4125);
DISPLAY 0.872340 (-6000 4125);
DISPLAY INVISIBLE (-6000 4125);
FORCEPROP 1 LAST PATH I268
J 2
(-5673 4250);
DISPLAY 0.872340 (-5673 4250);
PAINT GREEN (-5673 4250);
DISPLAY INVISIBLE (-5673 4250);
FORCEADD TAP..1
R 2
(-5675 4150);
FORCEPROP 3 LASTPIN (-5625 4150) SIG_NAME M_J_CPU1_SB_DQS_DP<7>
J 0
(-5615 4160);
DISPLAY 0.659574 (-5615 4160);
PAINT MONO (-5615 4160);
DISPLAY INVISIBLE (-5615 4160);
FORCEPROP 1 LASTPIN (-5625 4150) BN 7
J 2
(-5613 4158);
DISPLAY 0.489362 (-5613 4158);
PAINT GREEN (-5613 4158);
FORCEPROP 2 LAST CDS_LIB mstr_standard
J 2
(-5675 4150);
DISPLAY 0.723404 (-5675 4150);
PAINT MONO (-5675 4150);
DISPLAY INVISIBLE (-5675 4150);
FORCEPROP 1 LAST BODY_TYPE PLUMBING
J 2
(-5675 4200);
DISPLAY 0.872340 (-5675 4200);
PAINT GREEN (-5675 4200);
DISPLAY INVISIBLE (-5675 4200);
FORCEPROP 1 LAST HDL_TAP TRUE
J 2
(-6000 4025);
DISPLAY 0.872340 (-6000 4025);
DISPLAY INVISIBLE (-6000 4025);
FORCEPROP 1 LAST PATH I269
J 2
(-5673 4150);
DISPLAY 0.872340 (-5673 4150);
PAINT GREEN (-5673 4150);
DISPLAY INVISIBLE (-5673 4150);
FORCEADD TAP..1
R 2
(-5875 4950);
FORCEPROP 3 LASTPIN (-5825 4950) SIG_NAME M_J_CPU1_SA_DQS_DN<9>
J 0
(-5815 4960);
DISPLAY 0.659574 (-5815 4960);
PAINT MONO (-5815 4960);
DISPLAY INVISIBLE (-5815 4960);
FORCEPROP 1 LASTPIN (-5825 4950) BN 9
J 2
(-5813 4958);
DISPLAY 0.489362 (-5813 4958);
PAINT GREEN (-5813 4958);
FORCEPROP 2 LAST CDS_LIB mstr_standard
J 2
(-5875 4950);
DISPLAY 0.723404 (-5875 4950);
PAINT MONO (-5875 4950);
DISPLAY INVISIBLE (-5875 4950);
FORCEPROP 1 LAST BODY_TYPE PLUMBING
J 2
(-5875 5000);
DISPLAY 0.872340 (-5875 5000);
PAINT GREEN (-5875 5000);
DISPLAY INVISIBLE (-5875 5000);
FORCEPROP 1 LAST HDL_TAP TRUE
J 2
(-6200 4825);
DISPLAY 0.872340 (-6200 4825);
DISPLAY INVISIBLE (-6200 4825);
FORCEPROP 1 LAST PATH I270
J 2
(-5873 4950);
DISPLAY 0.872340 (-5873 4950);
PAINT GREEN (-5873 4950);
DISPLAY INVISIBLE (-5873 4950);
FORCEADD TAP..1
R 2
(-5875 5050);
FORCEPROP 3 LASTPIN (-5825 5050) SIG_NAME M_J_CPU1_SA_DQS_DN<8>
J 0
(-5815 5060);
DISPLAY 0.659574 (-5815 5060);
PAINT MONO (-5815 5060);
DISPLAY INVISIBLE (-5815 5060);
FORCEPROP 1 LASTPIN (-5825 5050) BN 8
J 2
(-5813 5058);
DISPLAY 0.489362 (-5813 5058);
PAINT GREEN (-5813 5058);
FORCEPROP 2 LAST CDS_LIB mstr_standard
J 2
(-5875 5050);
DISPLAY 0.723404 (-5875 5050);
PAINT MONO (-5875 5050);
DISPLAY INVISIBLE (-5875 5050);
FORCEPROP 1 LAST BODY_TYPE PLUMBING
J 2
(-5875 5100);
DISPLAY 0.872340 (-5875 5100);
PAINT GREEN (-5875 5100);
DISPLAY INVISIBLE (-5875 5100);
FORCEPROP 1 LAST HDL_TAP TRUE
J 2
(-6200 4925);
DISPLAY 0.872340 (-6200 4925);
DISPLAY INVISIBLE (-6200 4925);
FORCEPROP 1 LAST PATH I271
J 2
(-5873 5050);
DISPLAY 0.872340 (-5873 5050);
PAINT GREEN (-5873 5050);
DISPLAY INVISIBLE (-5873 5050);
FORCEADD TAP..1
R 2
(-5875 4800);
FORCEPROP 3 LASTPIN (-5825 4800) SIG_NAME M_J_CPU1_SB_DQS_DN<0>
J 0
(-5815 4810);
DISPLAY 0.659574 (-5815 4810);
PAINT MONO (-5815 4810);
DISPLAY INVISIBLE (-5815 4810);
FORCEPROP 1 LASTPIN (-5825 4800) BN 0
J 2
(-5813 4808);
DISPLAY 0.489362 (-5813 4808);
PAINT GREEN (-5813 4808);
FORCEPROP 2 LAST CDS_LIB mstr_standard
J 2
(-5875 4800);
DISPLAY 0.723404 (-5875 4800);
PAINT MONO (-5875 4800);
DISPLAY INVISIBLE (-5875 4800);
FORCEPROP 1 LAST BODY_TYPE PLUMBING
J 2
(-5875 4850);
DISPLAY 0.872340 (-5875 4850);
PAINT GREEN (-5875 4850);
DISPLAY INVISIBLE (-5875 4850);
FORCEPROP 1 LAST HDL_TAP TRUE
J 2
(-6200 4675);
DISPLAY 0.872340 (-6200 4675);
DISPLAY INVISIBLE (-6200 4675);
FORCEPROP 1 LAST PATH I272
J 2
(-5873 4800);
DISPLAY 0.872340 (-5873 4800);
PAINT GREEN (-5873 4800);
DISPLAY INVISIBLE (-5873 4800);
FORCEADD TAP..1
R 2
(-5875 4700);
FORCEPROP 3 LASTPIN (-5825 4700) SIG_NAME M_J_CPU1_SB_DQS_DN<1>
J 0
(-5815 4710);
DISPLAY 0.659574 (-5815 4710);
PAINT MONO (-5815 4710);
DISPLAY INVISIBLE (-5815 4710);
FORCEPROP 1 LASTPIN (-5825 4700) BN 1
J 2
(-5813 4708);
DISPLAY 0.489362 (-5813 4708);
PAINT GREEN (-5813 4708);
FORCEPROP 2 LAST CDS_LIB mstr_standard
J 2
(-5875 4700);
DISPLAY 0.723404 (-5875 4700);
PAINT MONO (-5875 4700);
DISPLAY INVISIBLE (-5875 4700);
FORCEPROP 1 LAST BODY_TYPE PLUMBING
J 2
(-5875 4750);
DISPLAY 0.872340 (-5875 4750);
PAINT GREEN (-5875 4750);
DISPLAY INVISIBLE (-5875 4750);
FORCEPROP 1 LAST HDL_TAP TRUE
J 2
(-6200 4575);
DISPLAY 0.872340 (-6200 4575);
DISPLAY INVISIBLE (-6200 4575);
FORCEPROP 1 LAST PATH I273
J 2
(-5873 4700);
DISPLAY 0.872340 (-5873 4700);
PAINT GREEN (-5873 4700);
DISPLAY INVISIBLE (-5873 4700);
FORCEADD TAP..1
R 2
(-5875 4500);
FORCEPROP 3 LASTPIN (-5825 4500) SIG_NAME M_J_CPU1_SB_DQS_DN<3>
J 0
(-5815 4510);
DISPLAY 0.659574 (-5815 4510);
PAINT MONO (-5815 4510);
DISPLAY INVISIBLE (-5815 4510);
FORCEPROP 1 LASTPIN (-5825 4500) BN 3
J 2
(-5813 4508);
DISPLAY 0.489362 (-5813 4508);
PAINT GREEN (-5813 4508);
FORCEPROP 2 LAST CDS_LIB mstr_standard
J 2
(-5875 4500);
DISPLAY 0.723404 (-5875 4500);
PAINT MONO (-5875 4500);
DISPLAY INVISIBLE (-5875 4500);
FORCEPROP 1 LAST BODY_TYPE PLUMBING
J 2
(-5875 4550);
DISPLAY 0.872340 (-5875 4550);
PAINT GREEN (-5875 4550);
DISPLAY INVISIBLE (-5875 4550);
FORCEPROP 1 LAST HDL_TAP TRUE
J 2
(-6200 4375);
DISPLAY 0.872340 (-6200 4375);
DISPLAY INVISIBLE (-6200 4375);
FORCEPROP 1 LAST PATH I274
J 2
(-5873 4500);
DISPLAY 0.872340 (-5873 4500);
PAINT GREEN (-5873 4500);
DISPLAY INVISIBLE (-5873 4500);
FORCEADD TAP..1
R 2
(-5875 4600);
FORCEPROP 3 LASTPIN (-5825 4600) SIG_NAME M_J_CPU1_SB_DQS_DN<2>
J 0
(-5815 4610);
DISPLAY 0.659574 (-5815 4610);
PAINT MONO (-5815 4610);
DISPLAY INVISIBLE (-5815 4610);
FORCEPROP 1 LASTPIN (-5825 4600) BN 2
J 2
(-5813 4608);
DISPLAY 0.489362 (-5813 4608);
PAINT GREEN (-5813 4608);
FORCEPROP 2 LAST CDS_LIB mstr_standard
J 2
(-5875 4600);
DISPLAY 0.723404 (-5875 4600);
PAINT MONO (-5875 4600);
DISPLAY INVISIBLE (-5875 4600);
FORCEPROP 1 LAST BODY_TYPE PLUMBING
J 2
(-5875 4650);
DISPLAY 0.872340 (-5875 4650);
PAINT GREEN (-5875 4650);
DISPLAY INVISIBLE (-5875 4650);
FORCEPROP 1 LAST HDL_TAP TRUE
J 2
(-6200 4475);
DISPLAY 0.872340 (-6200 4475);
DISPLAY INVISIBLE (-6200 4475);
FORCEPROP 1 LAST PATH I275
J 2
(-5873 4600);
DISPLAY 0.872340 (-5873 4600);
PAINT GREEN (-5873 4600);
DISPLAY INVISIBLE (-5873 4600);
FORCEADD TAP..1
R 2
(-5875 4400);
FORCEPROP 3 LASTPIN (-5825 4400) SIG_NAME M_J_CPU1_SB_DQS_DN<4>
J 0
(-5815 4410);
DISPLAY 0.659574 (-5815 4410);
PAINT MONO (-5815 4410);
DISPLAY INVISIBLE (-5815 4410);
FORCEPROP 1 LASTPIN (-5825 4400) BN 4
J 2
(-5813 4408);
DISPLAY 0.489362 (-5813 4408);
PAINT GREEN (-5813 4408);
FORCEPROP 2 LAST CDS_LIB mstr_standard
J 2
(-5875 4400);
DISPLAY 0.723404 (-5875 4400);
PAINT MONO (-5875 4400);
DISPLAY INVISIBLE (-5875 4400);
FORCEPROP 1 LAST BODY_TYPE PLUMBING
J 2
(-5875 4450);
DISPLAY 0.872340 (-5875 4450);
PAINT GREEN (-5875 4450);
DISPLAY INVISIBLE (-5875 4450);
FORCEPROP 1 LAST HDL_TAP TRUE
J 2
(-6200 4275);
DISPLAY 0.872340 (-6200 4275);
DISPLAY INVISIBLE (-6200 4275);
FORCEPROP 1 LAST PATH I276
J 2
(-5873 4400);
DISPLAY 0.872340 (-5873 4400);
PAINT GREEN (-5873 4400);
DISPLAY INVISIBLE (-5873 4400);
FORCEADD TAP..1
R 2
(-5875 4300);
FORCEPROP 3 LASTPIN (-5825 4300) SIG_NAME M_J_CPU1_SB_DQS_DN<5>
J 0
(-5815 4310);
DISPLAY 0.659574 (-5815 4310);
PAINT MONO (-5815 4310);
DISPLAY INVISIBLE (-5815 4310);
FORCEPROP 1 LASTPIN (-5825 4300) BN 5
J 2
(-5813 4308);
DISPLAY 0.489362 (-5813 4308);
PAINT GREEN (-5813 4308);
FORCEPROP 2 LAST CDS_LIB mstr_standard
J 2
(-5875 4300);
DISPLAY 0.723404 (-5875 4300);
PAINT MONO (-5875 4300);
DISPLAY INVISIBLE (-5875 4300);
FORCEPROP 1 LAST BODY_TYPE PLUMBING
J 2
(-5875 4350);
DISPLAY 0.872340 (-5875 4350);
PAINT GREEN (-5875 4350);
DISPLAY INVISIBLE (-5875 4350);
FORCEPROP 1 LAST HDL_TAP TRUE
J 2
(-6200 4175);
DISPLAY 0.872340 (-6200 4175);
DISPLAY INVISIBLE (-6200 4175);
FORCEPROP 1 LAST PATH I277
J 2
(-5873 4300);
DISPLAY 0.872340 (-5873 4300);
PAINT GREEN (-5873 4300);
DISPLAY INVISIBLE (-5873 4300);
FORCEADD TAP..1
R 2
(-5875 4100);
FORCEPROP 3 LASTPIN (-5825 4100) SIG_NAME M_J_CPU1_SB_DQS_DN<7>
J 0
(-5815 4110);
DISPLAY 0.659574 (-5815 4110);
PAINT MONO (-5815 4110);
DISPLAY INVISIBLE (-5815 4110);
FORCEPROP 1 LASTPIN (-5825 4100) BN 7
J 2
(-5813 4108);
DISPLAY 0.489362 (-5813 4108);
PAINT GREEN (-5813 4108);
FORCEPROP 2 LAST CDS_LIB mstr_standard
J 2
(-5875 4100);
DISPLAY 0.723404 (-5875 4100);
PAINT MONO (-5875 4100);
DISPLAY INVISIBLE (-5875 4100);
FORCEPROP 1 LAST BODY_TYPE PLUMBING
J 2
(-5875 4150);
DISPLAY 0.872340 (-5875 4150);
PAINT GREEN (-5875 4150);
DISPLAY INVISIBLE (-5875 4150);
FORCEPROP 1 LAST HDL_TAP TRUE
J 2
(-6200 3975);
DISPLAY 0.872340 (-6200 3975);
DISPLAY INVISIBLE (-6200 3975);
FORCEPROP 1 LAST PATH I278
J 2
(-5873 4100);
DISPLAY 0.872340 (-5873 4100);
PAINT GREEN (-5873 4100);
DISPLAY INVISIBLE (-5873 4100);
FORCEADD TAP..1
R 2
(-5875 4200);
FORCEPROP 3 LASTPIN (-5825 4200) SIG_NAME M_J_CPU1_SB_DQS_DN<6>
J 0
(-5815 4210);
DISPLAY 0.659574 (-5815 4210);
PAINT MONO (-5815 4210);
DISPLAY INVISIBLE (-5815 4210);
FORCEPROP 1 LASTPIN (-5825 4200) BN 6
J 2
(-5813 4208);
DISPLAY 0.489362 (-5813 4208);
PAINT GREEN (-5813 4208);
FORCEPROP 2 LAST CDS_LIB mstr_standard
J 2
(-5875 4200);
DISPLAY 0.723404 (-5875 4200);
PAINT MONO (-5875 4200);
DISPLAY INVISIBLE (-5875 4200);
FORCEPROP 1 LAST BODY_TYPE PLUMBING
J 2
(-5875 4250);
DISPLAY 0.872340 (-5875 4250);
PAINT GREEN (-5875 4250);
DISPLAY INVISIBLE (-5875 4250);
FORCEPROP 1 LAST HDL_TAP TRUE
J 2
(-6200 4075);
DISPLAY 0.872340 (-6200 4075);
DISPLAY INVISIBLE (-6200 4075);
FORCEPROP 1 LAST PATH I279
J 2
(-5873 4200);
DISPLAY 0.872340 (-5873 4200);
PAINT GREEN (-5873 4200);
DISPLAY INVISIBLE (-5873 4200);
FORCEADD OFFPAGE..3
R 2
(-6575 5875);
FORCEPROP 2 LAST $XR0 106 
J 0
(-6885 5875);
DISPLAY 0.638298 (-6885 5875);
PAINT MONO (-6885 5875);
FORCEPROP 2 LAST PATH I280
J 0
(-6875 5925);
DISPLAY 1.021277 (-6875 5925);
DISPLAY INVISIBLE (-6875 5925);
FORCEPROP 1 LAST COMMENT_BODY TRUE
J 2
(-6525 5775);
DISPLAY 0.872340 (-6525 5775);
PAINT GREEN (-6525 5775);
DISPLAY INVISIBLE (-6525 5775);
FORCEPROP 1 LAST OFFPAGE TRUE
J 2
(-6900 5750);
DISPLAY 0.872340 (-6900 5750);
PAINT GREEN (-6900 5750);
DISPLAY INVISIBLE (-6900 5750);
FORCEPROP 2 LAST CDS_LIB standard
J 0
(-6575 5875);
DISPLAY INVISIBLE (-6575 5875);
FORCEADD OFFPAGE..3
R 2
(-6575 5925);
FORCEPROP 2 LAST $XR0 106 
J 0
(-6885 5925);
DISPLAY 0.638298 (-6885 5925);
PAINT MONO (-6885 5925);
FORCEPROP 2 LAST PATH I281
J 0
(-6875 5975);
DISPLAY 1.021277 (-6875 5975);
DISPLAY INVISIBLE (-6875 5975);
FORCEPROP 1 LAST COMMENT_BODY TRUE
J 2
(-6525 5825);
DISPLAY 0.872340 (-6525 5825);
PAINT GREEN (-6525 5825);
DISPLAY INVISIBLE (-6525 5825);
FORCEPROP 1 LAST OFFPAGE TRUE
J 2
(-6900 5800);
DISPLAY 0.872340 (-6900 5800);
PAINT GREEN (-6900 5800);
DISPLAY INVISIBLE (-6900 5800);
FORCEPROP 2 LAST CDS_LIB standard
J 0
(-6575 5925);
DISPLAY INVISIBLE (-6575 5925);
FORCEADD OFFPAGE..3
R 2
(-6575 4825);
FORCEPROP 2 LAST $XR0 106 
J 0
(-6885 4825);
DISPLAY 0.638298 (-6885 4825);
PAINT MONO (-6885 4825);
FORCEPROP 2 LAST PATH I282
J 0
(-6875 4875);
DISPLAY 1.021277 (-6875 4875);
DISPLAY INVISIBLE (-6875 4875);
FORCEPROP 1 LAST COMMENT_BODY TRUE
J 2
(-6525 4725);
DISPLAY 0.872340 (-6525 4725);
PAINT GREEN (-6525 4725);
DISPLAY INVISIBLE (-6525 4725);
FORCEPROP 1 LAST OFFPAGE TRUE
J 2
(-6900 4700);
DISPLAY 0.872340 (-6900 4700);
PAINT GREEN (-6900 4700);
DISPLAY INVISIBLE (-6900 4700);
FORCEPROP 2 LAST CDS_LIB standard
J 0
(-6575 4825);
DISPLAY INVISIBLE (-6575 4825);
FORCEADD OFFPAGE..3
R 2
(-6575 4875);
FORCEPROP 2 LAST $XR0 106 
J 0
(-6885 4875);
DISPLAY 0.638298 (-6885 4875);
PAINT MONO (-6885 4875);
FORCEPROP 2 LAST PATH I283
J 0
(-6875 4925);
DISPLAY 1.021277 (-6875 4925);
DISPLAY INVISIBLE (-6875 4925);
FORCEPROP 1 LAST COMMENT_BODY TRUE
J 2
(-6525 4775);
DISPLAY 0.872340 (-6525 4775);
PAINT GREEN (-6525 4775);
DISPLAY INVISIBLE (-6525 4775);
FORCEPROP 1 LAST OFFPAGE TRUE
J 2
(-6900 4750);
DISPLAY 0.872340 (-6900 4750);
PAINT GREEN (-6900 4750);
DISPLAY INVISIBLE (-6900 4750);
FORCEPROP 2 LAST CDS_LIB standard
J 0
(-6575 4875);
DISPLAY INVISIBLE (-6575 4875);
FORCEADD TAP..1
R 2
(-5675 4050);
FORCEPROP 3 LASTPIN (-5625 4050) SIG_NAME M_J_CPU1_SB_DQS_DP<8>
J 0
(-5615 4060);
DISPLAY 0.659574 (-5615 4060);
PAINT MONO (-5615 4060);
DISPLAY INVISIBLE (-5615 4060);
FORCEPROP 1 LASTPIN (-5625 4050) BN 8
J 2
(-5613 4058);
DISPLAY 0.489362 (-5613 4058);
PAINT GREEN (-5613 4058);
FORCEPROP 2 LAST CDS_LIB mstr_standard
J 2
(-5675 4050);
DISPLAY 0.723404 (-5675 4050);
PAINT MONO (-5675 4050);
DISPLAY INVISIBLE (-5675 4050);
FORCEPROP 1 LAST BODY_TYPE PLUMBING
J 2
(-5675 4100);
DISPLAY 0.872340 (-5675 4100);
PAINT GREEN (-5675 4100);
DISPLAY INVISIBLE (-5675 4100);
FORCEPROP 1 LAST HDL_TAP TRUE
J 2
(-6000 3925);
DISPLAY 0.872340 (-6000 3925);
DISPLAY INVISIBLE (-6000 3925);
FORCEPROP 1 LAST PATH I284
J 2
(-5673 4050);
DISPLAY 0.872340 (-5673 4050);
PAINT GREEN (-5673 4050);
DISPLAY INVISIBLE (-5673 4050);
FORCEADD TAP..1
R 2
(-5675 3950);
FORCEPROP 3 LASTPIN (-5625 3950) SIG_NAME M_J_CPU1_SB_DQS_DP<9>
J 0
(-5615 3960);
DISPLAY 0.659574 (-5615 3960);
PAINT MONO (-5615 3960);
DISPLAY INVISIBLE (-5615 3960);
FORCEPROP 1 LASTPIN (-5625 3950) BN 9
J 2
(-5613 3958);
DISPLAY 0.489362 (-5613 3958);
PAINT GREEN (-5613 3958);
FORCEPROP 2 LAST CDS_LIB mstr_standard
J 2
(-5675 3950);
DISPLAY 0.723404 (-5675 3950);
PAINT MONO (-5675 3950);
DISPLAY INVISIBLE (-5675 3950);
FORCEPROP 1 LAST BODY_TYPE PLUMBING
J 2
(-5675 4000);
DISPLAY 0.872340 (-5675 4000);
PAINT GREEN (-5675 4000);
DISPLAY INVISIBLE (-5675 4000);
FORCEPROP 1 LAST HDL_TAP TRUE
J 2
(-6000 3825);
DISPLAY 0.872340 (-6000 3825);
DISPLAY INVISIBLE (-6000 3825);
FORCEPROP 1 LAST PATH I285
J 2
(-5673 3950);
DISPLAY 0.872340 (-5673 3950);
PAINT GREEN (-5673 3950);
DISPLAY INVISIBLE (-5673 3950);
FORCEADD TAP..1
R 2
(-5875 4000);
FORCEPROP 3 LASTPIN (-5825 4000) SIG_NAME M_J_CPU1_SB_DQS_DN<8>
J 0
(-5815 4010);
DISPLAY 0.659574 (-5815 4010);
PAINT MONO (-5815 4010);
DISPLAY INVISIBLE (-5815 4010);
FORCEPROP 1 LASTPIN (-5825 4000) BN 8
J 2
(-5813 4008);
DISPLAY 0.489362 (-5813 4008);
PAINT GREEN (-5813 4008);
FORCEPROP 2 LAST CDS_LIB mstr_standard
J 2
(-5875 4000);
DISPLAY 0.723404 (-5875 4000);
PAINT MONO (-5875 4000);
DISPLAY INVISIBLE (-5875 4000);
FORCEPROP 1 LAST BODY_TYPE PLUMBING
J 2
(-5875 4050);
DISPLAY 0.872340 (-5875 4050);
PAINT GREEN (-5875 4050);
DISPLAY INVISIBLE (-5875 4050);
FORCEPROP 1 LAST HDL_TAP TRUE
J 2
(-6200 3875);
DISPLAY 0.872340 (-6200 3875);
DISPLAY INVISIBLE (-6200 3875);
FORCEPROP 1 LAST PATH I286
J 2
(-5873 4000);
DISPLAY 0.872340 (-5873 4000);
PAINT GREEN (-5873 4000);
DISPLAY INVISIBLE (-5873 4000);
FORCEADD TAP..1
R 2
(-5875 3900);
FORCEPROP 3 LASTPIN (-5825 3900) SIG_NAME M_J_CPU1_SB_DQS_DN<9>
J 0
(-5815 3910);
DISPLAY 0.659574 (-5815 3910);
PAINT MONO (-5815 3910);
DISPLAY INVISIBLE (-5815 3910);
FORCEPROP 1 LASTPIN (-5825 3900) BN 9
J 2
(-5813 3908);
DISPLAY 0.489362 (-5813 3908);
PAINT GREEN (-5813 3908);
FORCEPROP 2 LAST CDS_LIB mstr_standard
J 2
(-5875 3900);
DISPLAY 0.723404 (-5875 3900);
PAINT MONO (-5875 3900);
DISPLAY INVISIBLE (-5875 3900);
FORCEPROP 1 LAST BODY_TYPE PLUMBING
J 2
(-5875 3950);
DISPLAY 0.872340 (-5875 3950);
PAINT GREEN (-5875 3950);
DISPLAY INVISIBLE (-5875 3950);
FORCEPROP 1 LAST HDL_TAP TRUE
J 2
(-6200 3775);
DISPLAY 0.872340 (-6200 3775);
DISPLAY INVISIBLE (-6200 3775);
FORCEPROP 1 LAST PATH I287
J 2
(-5873 3900);
DISPLAY 0.872340 (-5873 3900);
PAINT GREEN (-5873 3900);
DISPLAY INVISIBLE (-5873 3900);
FORCEADD TAP..1
R 2
(-5875 3750);
FORCEPROP 3 LASTPIN (-5825 3750) SIG_NAME M_J_CPU1_SA_CA<0>
J 0
(-5815 3760);
DISPLAY 0.659574 (-5815 3760);
PAINT MONO (-5815 3760);
DISPLAY INVISIBLE (-5815 3760);
FORCEPROP 1 LASTPIN (-5825 3750) BN 0
J 2
(-5813 3758);
DISPLAY 0.489362 (-5813 3758);
PAINT GREEN (-5813 3758);
FORCEPROP 2 LAST CDS_LIB mstr_standard
J 0
(-5875 3750);
DISPLAY 0.723404 (-5875 3750);
PAINT MONO (-5875 3750);
DISPLAY INVISIBLE (-5875 3750);
FORCEPROP 1 LAST BODY_TYPE PLUMBING
J 2
(-5875 3800);
DISPLAY 0.872340 (-5875 3800);
PAINT GREEN (-5875 3800);
DISPLAY INVISIBLE (-5875 3800);
FORCEPROP 1 LAST HDL_TAP TRUE
J 2
(-6200 3625);
DISPLAY 0.872340 (-6200 3625);
DISPLAY INVISIBLE (-6200 3625);
FORCEPROP 1 LAST PATH I288
J 2
(-5873 3750);
DISPLAY 0.872340 (-5873 3750);
PAINT GREEN (-5873 3750);
DISPLAY INVISIBLE (-5873 3750);
FORCEADD TAP..1
R 2
(-5875 3700);
FORCEPROP 3 LASTPIN (-5825 3700) SIG_NAME M_J_CPU1_SA_CA<1>
J 0
(-5815 3710);
DISPLAY 0.659574 (-5815 3710);
PAINT MONO (-5815 3710);
DISPLAY INVISIBLE (-5815 3710);
FORCEPROP 1 LASTPIN (-5825 3700) BN 1
J 2
(-5813 3708);
DISPLAY 0.489362 (-5813 3708);
PAINT GREEN (-5813 3708);
FORCEPROP 2 LAST CDS_LIB mstr_standard
J 0
(-5875 3700);
DISPLAY 0.723404 (-5875 3700);
PAINT MONO (-5875 3700);
DISPLAY INVISIBLE (-5875 3700);
FORCEPROP 1 LAST BODY_TYPE PLUMBING
J 2
(-5875 3750);
DISPLAY 0.872340 (-5875 3750);
PAINT GREEN (-5875 3750);
DISPLAY INVISIBLE (-5875 3750);
FORCEPROP 1 LAST HDL_TAP TRUE
J 2
(-6200 3575);
DISPLAY 0.872340 (-6200 3575);
DISPLAY INVISIBLE (-6200 3575);
FORCEPROP 1 LAST PATH I289
J 2
(-5873 3700);
DISPLAY 0.872340 (-5873 3700);
PAINT GREEN (-5873 3700);
DISPLAY INVISIBLE (-5873 3700);
FORCEADD TAP..1
R 2
(-5875 3600);
FORCEPROP 3 LASTPIN (-5825 3600) SIG_NAME M_J_CPU1_SA_CA<3>
J 0
(-5815 3610);
DISPLAY 0.659574 (-5815 3610);
PAINT MONO (-5815 3610);
DISPLAY INVISIBLE (-5815 3610);
FORCEPROP 1 LASTPIN (-5825 3600) BN 3
J 2
(-5813 3608);
DISPLAY 0.489362 (-5813 3608);
PAINT GREEN (-5813 3608);
FORCEPROP 2 LAST CDS_LIB mstr_standard
J 0
(-5875 3600);
DISPLAY 0.723404 (-5875 3600);
PAINT MONO (-5875 3600);
DISPLAY INVISIBLE (-5875 3600);
FORCEPROP 1 LAST BODY_TYPE PLUMBING
J 2
(-5875 3650);
DISPLAY 0.872340 (-5875 3650);
PAINT GREEN (-5875 3650);
DISPLAY INVISIBLE (-5875 3650);
FORCEPROP 1 LAST HDL_TAP TRUE
J 2
(-6200 3475);
DISPLAY 0.872340 (-6200 3475);
DISPLAY INVISIBLE (-6200 3475);
FORCEPROP 1 LAST PATH I290
J 2
(-5873 3600);
DISPLAY 0.872340 (-5873 3600);
PAINT GREEN (-5873 3600);
DISPLAY INVISIBLE (-5873 3600);
FORCEADD TAP..1
R 2
(-5875 3650);
FORCEPROP 3 LASTPIN (-5825 3650) SIG_NAME M_J_CPU1_SA_CA<2>
J 0
(-5815 3660);
DISPLAY 0.659574 (-5815 3660);
PAINT MONO (-5815 3660);
DISPLAY INVISIBLE (-5815 3660);
FORCEPROP 1 LASTPIN (-5825 3650) BN 2
J 2
(-5813 3658);
DISPLAY 0.489362 (-5813 3658);
PAINT GREEN (-5813 3658);
FORCEPROP 2 LAST CDS_LIB mstr_standard
J 0
(-5875 3650);
DISPLAY 0.723404 (-5875 3650);
PAINT MONO (-5875 3650);
DISPLAY INVISIBLE (-5875 3650);
FORCEPROP 1 LAST BODY_TYPE PLUMBING
J 2
(-5875 3700);
DISPLAY 0.872340 (-5875 3700);
PAINT GREEN (-5875 3700);
DISPLAY INVISIBLE (-5875 3700);
FORCEPROP 1 LAST HDL_TAP TRUE
J 2
(-6200 3525);
DISPLAY 0.872340 (-6200 3525);
DISPLAY INVISIBLE (-6200 3525);
FORCEPROP 1 LAST PATH I291
J 2
(-5873 3650);
DISPLAY 0.872340 (-5873 3650);
PAINT GREEN (-5873 3650);
DISPLAY INVISIBLE (-5873 3650);
FORCEADD TAP..1
R 2
(-5875 3550);
FORCEPROP 3 LASTPIN (-5825 3550) SIG_NAME M_J_CPU1_SA_CA<4>
J 0
(-5815 3560);
DISPLAY 0.659574 (-5815 3560);
PAINT MONO (-5815 3560);
DISPLAY INVISIBLE (-5815 3560);
FORCEPROP 1 LASTPIN (-5825 3550) BN 4
J 2
(-5813 3558);
DISPLAY 0.489362 (-5813 3558);
PAINT GREEN (-5813 3558);
FORCEPROP 2 LAST CDS_LIB mstr_standard
J 0
(-5875 3550);
DISPLAY 0.723404 (-5875 3550);
PAINT MONO (-5875 3550);
DISPLAY INVISIBLE (-5875 3550);
FORCEPROP 1 LAST BODY_TYPE PLUMBING
J 2
(-5875 3600);
DISPLAY 0.872340 (-5875 3600);
PAINT GREEN (-5875 3600);
DISPLAY INVISIBLE (-5875 3600);
FORCEPROP 1 LAST HDL_TAP TRUE
J 2
(-6200 3425);
DISPLAY 0.872340 (-6200 3425);
DISPLAY INVISIBLE (-6200 3425);
FORCEPROP 1 LAST PATH I292
J 2
(-5873 3550);
DISPLAY 0.872340 (-5873 3550);
PAINT GREEN (-5873 3550);
DISPLAY INVISIBLE (-5873 3550);
FORCEADD TAP..1
R 2
(-5875 3500);
FORCEPROP 3 LASTPIN (-5825 3500) SIG_NAME M_J_CPU1_SA_CA<5>
J 0
(-5815 3510);
DISPLAY 0.659574 (-5815 3510);
PAINT MONO (-5815 3510);
DISPLAY INVISIBLE (-5815 3510);
FORCEPROP 1 LASTPIN (-5825 3500) BN 5
J 2
(-5813 3508);
DISPLAY 0.489362 (-5813 3508);
PAINT GREEN (-5813 3508);
FORCEPROP 2 LAST CDS_LIB mstr_standard
J 0
(-5875 3500);
DISPLAY 0.723404 (-5875 3500);
PAINT MONO (-5875 3500);
DISPLAY INVISIBLE (-5875 3500);
FORCEPROP 1 LAST BODY_TYPE PLUMBING
J 2
(-5875 3550);
DISPLAY 0.872340 (-5875 3550);
PAINT GREEN (-5875 3550);
DISPLAY INVISIBLE (-5875 3550);
FORCEPROP 1 LAST HDL_TAP TRUE
J 2
(-6200 3375);
DISPLAY 0.872340 (-6200 3375);
DISPLAY INVISIBLE (-6200 3375);
FORCEPROP 1 LAST PATH I293
J 2
(-5873 3500);
DISPLAY 0.872340 (-5873 3500);
PAINT GREEN (-5873 3500);
DISPLAY INVISIBLE (-5873 3500);
FORCEADD TAP..1
R 2
(-5875 3450);
FORCEPROP 3 LASTPIN (-5825 3450) SIG_NAME M_J_CPU1_SA_CA<6>
J 0
(-5815 3460);
DISPLAY 0.659574 (-5815 3460);
PAINT MONO (-5815 3460);
DISPLAY INVISIBLE (-5815 3460);
FORCEPROP 1 LASTPIN (-5825 3450) BN 6
J 2
(-5813 3458);
DISPLAY 0.489362 (-5813 3458);
PAINT GREEN (-5813 3458);
FORCEPROP 2 LAST CDS_LIB mstr_standard
J 0
(-5875 3450);
DISPLAY 0.723404 (-5875 3450);
PAINT MONO (-5875 3450);
DISPLAY INVISIBLE (-5875 3450);
FORCEPROP 1 LAST BODY_TYPE PLUMBING
J 2
(-5875 3500);
DISPLAY 0.872340 (-5875 3500);
PAINT GREEN (-5875 3500);
DISPLAY INVISIBLE (-5875 3500);
FORCEPROP 1 LAST HDL_TAP TRUE
J 2
(-6200 3325);
DISPLAY 0.872340 (-6200 3325);
DISPLAY INVISIBLE (-6200 3325);
FORCEPROP 1 LAST PATH I294
J 2
(-5873 3450);
DISPLAY 0.872340 (-5873 3450);
PAINT GREEN (-5873 3450);
DISPLAY INVISIBLE (-5873 3450);
FORCEADD TAP..1
R 2
(-5875 3350);
FORCEPROP 3 LASTPIN (-5825 3350) SIG_NAME M_J_CPU1_SB_CA<0>
J 0
(-5815 3360);
DISPLAY 0.659574 (-5815 3360);
PAINT MONO (-5815 3360);
DISPLAY INVISIBLE (-5815 3360);
FORCEPROP 1 LASTPIN (-5825 3350) BN 0
J 2
(-5813 3358);
DISPLAY 0.489362 (-5813 3358);
PAINT GREEN (-5813 3358);
FORCEPROP 2 LAST CDS_LIB mstr_standard
J 0
(-5875 3350);
DISPLAY 0.723404 (-5875 3350);
PAINT MONO (-5875 3350);
DISPLAY INVISIBLE (-5875 3350);
FORCEPROP 1 LAST BODY_TYPE PLUMBING
J 2
(-5875 3400);
DISPLAY 0.872340 (-5875 3400);
PAINT GREEN (-5875 3400);
DISPLAY INVISIBLE (-5875 3400);
FORCEPROP 1 LAST HDL_TAP TRUE
J 2
(-6200 3225);
DISPLAY 0.872340 (-6200 3225);
DISPLAY INVISIBLE (-6200 3225);
FORCEPROP 1 LAST PATH I295
J 2
(-5873 3350);
DISPLAY 0.872340 (-5873 3350);
PAINT GREEN (-5873 3350);
DISPLAY INVISIBLE (-5873 3350);
FORCEADD TAP..1
R 2
(-5875 3250);
FORCEPROP 3 LASTPIN (-5825 3250) SIG_NAME M_J_CPU1_SB_CA<2>
J 0
(-5815 3260);
DISPLAY 0.659574 (-5815 3260);
PAINT MONO (-5815 3260);
DISPLAY INVISIBLE (-5815 3260);
FORCEPROP 1 LASTPIN (-5825 3250) BN 2
J 2
(-5813 3258);
DISPLAY 0.489362 (-5813 3258);
PAINT GREEN (-5813 3258);
FORCEPROP 2 LAST CDS_LIB mstr_standard
J 0
(-5875 3250);
DISPLAY 0.723404 (-5875 3250);
PAINT MONO (-5875 3250);
DISPLAY INVISIBLE (-5875 3250);
FORCEPROP 1 LAST BODY_TYPE PLUMBING
J 2
(-5875 3300);
DISPLAY 0.872340 (-5875 3300);
PAINT GREEN (-5875 3300);
DISPLAY INVISIBLE (-5875 3300);
FORCEPROP 1 LAST HDL_TAP TRUE
J 2
(-6200 3125);
DISPLAY 0.872340 (-6200 3125);
DISPLAY INVISIBLE (-6200 3125);
FORCEPROP 1 LAST PATH I296
J 2
(-5873 3250);
DISPLAY 0.872340 (-5873 3250);
PAINT GREEN (-5873 3250);
DISPLAY INVISIBLE (-5873 3250);
FORCEADD TAP..1
R 2
(-5875 3300);
FORCEPROP 3 LASTPIN (-5825 3300) SIG_NAME M_J_CPU1_SB_CA<1>
J 0
(-5815 3310);
DISPLAY 0.659574 (-5815 3310);
PAINT MONO (-5815 3310);
DISPLAY INVISIBLE (-5815 3310);
FORCEPROP 1 LASTPIN (-5825 3300) BN 1
J 2
(-5813 3308);
DISPLAY 0.489362 (-5813 3308);
PAINT GREEN (-5813 3308);
FORCEPROP 2 LAST CDS_LIB mstr_standard
J 0
(-5875 3300);
DISPLAY 0.723404 (-5875 3300);
PAINT MONO (-5875 3300);
DISPLAY INVISIBLE (-5875 3300);
FORCEPROP 1 LAST BODY_TYPE PLUMBING
J 2
(-5875 3350);
DISPLAY 0.872340 (-5875 3350);
PAINT GREEN (-5875 3350);
DISPLAY INVISIBLE (-5875 3350);
FORCEPROP 1 LAST HDL_TAP TRUE
J 2
(-6200 3175);
DISPLAY 0.872340 (-6200 3175);
DISPLAY INVISIBLE (-6200 3175);
FORCEPROP 1 LAST PATH I297
J 2
(-5873 3300);
DISPLAY 0.872340 (-5873 3300);
PAINT GREEN (-5873 3300);
DISPLAY INVISIBLE (-5873 3300);
FORCEADD TAP..1
R 2
(-5875 3200);
FORCEPROP 3 LASTPIN (-5825 3200) SIG_NAME M_J_CPU1_SB_CA<3>
J 0
(-5815 3210);
DISPLAY 0.659574 (-5815 3210);
PAINT MONO (-5815 3210);
DISPLAY INVISIBLE (-5815 3210);
FORCEPROP 1 LASTPIN (-5825 3200) BN 3
J 2
(-5813 3208);
DISPLAY 0.489362 (-5813 3208);
PAINT GREEN (-5813 3208);
FORCEPROP 2 LAST CDS_LIB mstr_standard
J 0
(-5875 3200);
DISPLAY 0.723404 (-5875 3200);
PAINT MONO (-5875 3200);
DISPLAY INVISIBLE (-5875 3200);
FORCEPROP 1 LAST BODY_TYPE PLUMBING
J 2
(-5875 3250);
DISPLAY 0.872340 (-5875 3250);
PAINT GREEN (-5875 3250);
DISPLAY INVISIBLE (-5875 3250);
FORCEPROP 1 LAST HDL_TAP TRUE
J 2
(-6200 3075);
DISPLAY 0.872340 (-6200 3075);
DISPLAY INVISIBLE (-6200 3075);
FORCEPROP 1 LAST PATH I298
J 2
(-5873 3200);
DISPLAY 0.872340 (-5873 3200);
PAINT GREEN (-5873 3200);
DISPLAY INVISIBLE (-5873 3200);
FORCEADD TAP..1
R 2
(-5875 3150);
FORCEPROP 3 LASTPIN (-5825 3150) SIG_NAME M_J_CPU1_SB_CA<4>
J 0
(-5815 3160);
DISPLAY 0.659574 (-5815 3160);
PAINT MONO (-5815 3160);
DISPLAY INVISIBLE (-5815 3160);
FORCEPROP 1 LASTPIN (-5825 3150) BN 4
J 2
(-5813 3158);
DISPLAY 0.489362 (-5813 3158);
PAINT GREEN (-5813 3158);
FORCEPROP 2 LAST CDS_LIB mstr_standard
J 0
(-5875 3150);
DISPLAY 0.723404 (-5875 3150);
PAINT MONO (-5875 3150);
DISPLAY INVISIBLE (-5875 3150);
FORCEPROP 1 LAST BODY_TYPE PLUMBING
J 2
(-5875 3200);
DISPLAY 0.872340 (-5875 3200);
PAINT GREEN (-5875 3200);
DISPLAY INVISIBLE (-5875 3200);
FORCEPROP 1 LAST HDL_TAP TRUE
J 2
(-6200 3025);
DISPLAY 0.872340 (-6200 3025);
DISPLAY INVISIBLE (-6200 3025);
FORCEPROP 1 LAST PATH I299
J 2
(-5873 3150);
DISPLAY 0.872340 (-5873 3150);
PAINT GREEN (-5873 3150);
DISPLAY INVISIBLE (-5873 3150);
FORCEADD TAP..1
R 2
(-5875 3100);
FORCEPROP 3 LASTPIN (-5825 3100) SIG_NAME M_J_CPU1_SB_CA<5>
J 0
(-5815 3110);
DISPLAY 0.659574 (-5815 3110);
PAINT MONO (-5815 3110);
DISPLAY INVISIBLE (-5815 3110);
FORCEPROP 1 LASTPIN (-5825 3100) BN 5
J 2
(-5813 3108);
DISPLAY 0.489362 (-5813 3108);
PAINT GREEN (-5813 3108);
FORCEPROP 2 LAST CDS_LIB mstr_standard
J 0
(-5875 3100);
DISPLAY 0.723404 (-5875 3100);
PAINT MONO (-5875 3100);
DISPLAY INVISIBLE (-5875 3100);
FORCEPROP 1 LAST BODY_TYPE PLUMBING
J 2
(-5875 3150);
DISPLAY 0.872340 (-5875 3150);
PAINT GREEN (-5875 3150);
DISPLAY INVISIBLE (-5875 3150);
FORCEPROP 1 LAST HDL_TAP TRUE
J 2
(-6200 2975);
DISPLAY 0.872340 (-6200 2975);
DISPLAY INVISIBLE (-6200 2975);
FORCEPROP 1 LAST PATH I300
J 2
(-5873 3100);
DISPLAY 0.872340 (-5873 3100);
PAINT GREEN (-5873 3100);
DISPLAY INVISIBLE (-5873 3100);
FORCEADD TAP..1
R 2
(-5875 3050);
FORCEPROP 3 LASTPIN (-5825 3050) SIG_NAME M_J_CPU1_SB_CA<6>
J 0
(-5815 3060);
DISPLAY 0.659574 (-5815 3060);
PAINT MONO (-5815 3060);
DISPLAY INVISIBLE (-5815 3060);
FORCEPROP 1 LASTPIN (-5825 3050) BN 6
J 2
(-5813 3058);
DISPLAY 0.489362 (-5813 3058);
PAINT GREEN (-5813 3058);
FORCEPROP 2 LAST CDS_LIB mstr_standard
J 0
(-5875 3050);
DISPLAY 0.723404 (-5875 3050);
PAINT MONO (-5875 3050);
DISPLAY INVISIBLE (-5875 3050);
FORCEPROP 1 LAST BODY_TYPE PLUMBING
J 2
(-5875 3100);
DISPLAY 0.872340 (-5875 3100);
PAINT GREEN (-5875 3100);
DISPLAY INVISIBLE (-5875 3100);
FORCEPROP 1 LAST HDL_TAP TRUE
J 2
(-6200 2925);
DISPLAY 0.872340 (-6200 2925);
DISPLAY INVISIBLE (-6200 2925);
FORCEPROP 1 LAST PATH I301
J 2
(-5873 3050);
DISPLAY 0.872340 (-5873 3050);
PAINT GREEN (-5873 3050);
DISPLAY INVISIBLE (-5873 3050);
FORCEADD OFFPAGE..2
R 2
(-6475 3775);
FORCEPROP 2 LAST $XR0 106 
J 0
(-6730 3775);
DISPLAY 0.638298 (-6730 3775);
PAINT MONO (-6730 3775);
FORCEPROP 2 LAST PATH I302
J 0
(-6750 3825);
DISPLAY 1.021277 (-6750 3825);
DISPLAY INVISIBLE (-6750 3825);
FORCEPROP 1 LAST COMMENT_BODY TRUE
J 2
(-6430 3680);
DISPLAY 0.872340 (-6430 3680);
PAINT GREEN (-6430 3680);
DISPLAY INVISIBLE (-6430 3680);
FORCEPROP 1 LAST OFFPAGE TRUE
J 2
(-6800 3650);
DISPLAY 0.872340 (-6800 3650);
PAINT GREEN (-6800 3650);
DISPLAY INVISIBLE (-6800 3650);
FORCEPROP 2 LAST CDS_LIB standard
J 0
(-6475 3775);
DISPLAY INVISIBLE (-6475 3775);
FORCEADD OFFPAGE..2
R 2
(-6475 3375);
FORCEPROP 2 LAST $XR0 106 
J 0
(-6730 3375);
DISPLAY 0.638298 (-6730 3375);
PAINT MONO (-6730 3375);
FORCEPROP 2 LAST PATH I303
J 0
(-6750 3425);
DISPLAY 1.021277 (-6750 3425);
DISPLAY INVISIBLE (-6750 3425);
FORCEPROP 1 LAST COMMENT_BODY TRUE
J 2
(-6430 3280);
DISPLAY 0.872340 (-6430 3280);
PAINT GREEN (-6430 3280);
DISPLAY INVISIBLE (-6430 3280);
FORCEPROP 1 LAST OFFPAGE TRUE
J 2
(-6800 3250);
DISPLAY 0.872340 (-6800 3250);
PAINT GREEN (-6800 3250);
DISPLAY INVISIBLE (-6800 3250);
FORCEPROP 2 LAST CDS_LIB standard
J 0
(-6475 3375);
DISPLAY INVISIBLE (-6475 3375);
FORCEADD OFFPAGE..2
R 2
(-6475 2900);
FORCEPROP 2 LAST $XR0 106 
J 0
(-6730 2900);
DISPLAY 0.638298 (-6730 2900);
PAINT MONO (-6730 2900);
FORCEPROP 2 LAST PATH I304
J 0
(-6750 2950);
DISPLAY 1.021277 (-6750 2950);
DISPLAY INVISIBLE (-6750 2950);
FORCEPROP 1 LAST COMMENT_BODY TRUE
J 2
(-6430 2805);
DISPLAY 0.872340 (-6430 2805);
PAINT GREEN (-6430 2805);
DISPLAY INVISIBLE (-6430 2805);
FORCEPROP 1 LAST OFFPAGE TRUE
J 2
(-6800 2775);
DISPLAY 0.872340 (-6800 2775);
PAINT GREEN (-6800 2775);
DISPLAY INVISIBLE (-6800 2775);
FORCEPROP 2 LAST CDS_LIB standard
J 0
(-6475 2900);
DISPLAY INVISIBLE (-6475 2900);
FORCEADD OFFPAGE..2
R 2
(-6475 2850);
FORCEPROP 2 LAST $XR0 106 
J 0
(-6730 2850);
DISPLAY 0.638298 (-6730 2850);
PAINT MONO (-6730 2850);
FORCEPROP 2 LAST PATH I305
J 0
(-6750 2900);
DISPLAY 1.021277 (-6750 2900);
DISPLAY INVISIBLE (-6750 2900);
FORCEPROP 1 LAST COMMENT_BODY TRUE
J 2
(-6430 2755);
DISPLAY 0.872340 (-6430 2755);
PAINT GREEN (-6430 2755);
DISPLAY INVISIBLE (-6430 2755);
FORCEPROP 1 LAST OFFPAGE TRUE
J 2
(-6800 2725);
DISPLAY 0.872340 (-6800 2725);
PAINT GREEN (-6800 2725);
DISPLAY INVISIBLE (-6800 2725);
FORCEPROP 2 LAST CDS_LIB standard
J 0
(-6475 2850);
DISPLAY INVISIBLE (-6475 2850);
FORCEADD OFFPAGE..2
R 2
(-6475 2750);
FORCEPROP 2 LAST $XR0 106 
J 0
(-6730 2750);
DISPLAY 0.638298 (-6730 2750);
PAINT MONO (-6730 2750);
FORCEPROP 2 LAST PATH I306
J 0
(-6750 2800);
DISPLAY 1.021277 (-6750 2800);
DISPLAY INVISIBLE (-6750 2800);
FORCEPROP 1 LAST COMMENT_BODY TRUE
J 2
(-6430 2655);
DISPLAY 0.872340 (-6430 2655);
PAINT GREEN (-6430 2655);
DISPLAY INVISIBLE (-6430 2655);
FORCEPROP 1 LAST OFFPAGE TRUE
J 2
(-6800 2625);
DISPLAY 0.872340 (-6800 2625);
PAINT GREEN (-6800 2625);
DISPLAY INVISIBLE (-6800 2625);
FORCEPROP 2 LAST CDS_LIB standard
J 0
(-6475 2750);
DISPLAY INVISIBLE (-6475 2750);
FORCEADD OFFPAGE..2
R 2
(-6475 2700);
FORCEPROP 2 LAST $XR0 106 
J 0
(-6730 2700);
DISPLAY 0.638298 (-6730 2700);
PAINT MONO (-6730 2700);
FORCEPROP 2 LAST PATH I307
J 0
(-6750 2750);
DISPLAY 1.021277 (-6750 2750);
DISPLAY INVISIBLE (-6750 2750);
FORCEPROP 1 LAST COMMENT_BODY TRUE
J 2
(-6430 2605);
DISPLAY 0.872340 (-6430 2605);
PAINT GREEN (-6430 2605);
DISPLAY INVISIBLE (-6430 2605);
FORCEPROP 1 LAST OFFPAGE TRUE
J 2
(-6800 2575);
DISPLAY 0.872340 (-6800 2575);
PAINT GREEN (-6800 2575);
DISPLAY INVISIBLE (-6800 2575);
FORCEPROP 2 LAST CDS_LIB standard
J 0
(-6475 2700);
DISPLAY INVISIBLE (-6475 2700);
FORCEADD OFFPAGE..1
(-6475 2600);
FORCEPROP 2 LAST $XR0 106 
J 0
(-6757 2600);
DISPLAY 0.638298 (-6757 2600);
PAINT MONO (-6757 2600);
FORCEPROP 2 LAST PATH I308
J 0
(-6725 2650);
DISPLAY 1.021277 (-6725 2650);
DISPLAY INVISIBLE (-6725 2650);
FORCEPROP 1 LAST COMMENT_BODY TRUE
J 0
(-6350 2500);
DISPLAY 0.872340 (-6350 2500);
PAINT GREEN (-6350 2500);
DISPLAY INVISIBLE (-6350 2500);
FORCEPROP 1 LAST OFFPAGE TRUE
J 0
(-6150 2475);
DISPLAY 0.872340 (-6150 2475);
PAINT GREEN (-6150 2475);
DISPLAY INVISIBLE (-6150 2475);
FORCEPROP 2 LAST CDS_LIB standard
J 0
(-6475 2600);
DISPLAY INVISIBLE (-6475 2600);
FORCEADD OFFPAGE..2
R 2
(-6475 2400);
FORCEPROP 2 LAST $XR0 106 
J 0
(-6730 2400);
DISPLAY 0.638298 (-6730 2400);
PAINT MONO (-6730 2400);
FORCEPROP 2 LAST PATH I309
J 0
(-6750 2450);
DISPLAY 1.021277 (-6750 2450);
DISPLAY INVISIBLE (-6750 2450);
FORCEPROP 1 LAST COMMENT_BODY TRUE
J 2
(-6430 2305);
DISPLAY 0.872340 (-6430 2305);
PAINT GREEN (-6430 2305);
DISPLAY INVISIBLE (-6430 2305);
FORCEPROP 1 LAST OFFPAGE TRUE
J 2
(-6800 2275);
DISPLAY 0.872340 (-6800 2275);
PAINT GREEN (-6800 2275);
DISPLAY INVISIBLE (-6800 2275);
FORCEPROP 2 LAST CDS_LIB standard
J 0
(-6475 2400);
DISPLAY INVISIBLE (-6475 2400);
FORCEADD OFFPAGE..2
R 2
(-6475 2350);
FORCEPROP 2 LAST $XR0 106 
J 0
(-6730 2350);
DISPLAY 0.638298 (-6730 2350);
PAINT MONO (-6730 2350);
FORCEPROP 2 LAST PATH I310
J 0
(-6750 2400);
DISPLAY 1.021277 (-6750 2400);
DISPLAY INVISIBLE (-6750 2400);
FORCEPROP 1 LAST COMMENT_BODY TRUE
J 2
(-6430 2255);
DISPLAY 0.872340 (-6430 2255);
PAINT GREEN (-6430 2255);
DISPLAY INVISIBLE (-6430 2255);
FORCEPROP 1 LAST OFFPAGE TRUE
J 2
(-6800 2225);
DISPLAY 0.872340 (-6800 2225);
PAINT GREEN (-6800 2225);
DISPLAY INVISIBLE (-6800 2225);
FORCEPROP 2 LAST CDS_LIB standard
J 0
(-6475 2350);
DISPLAY INVISIBLE (-6475 2350);
FORCEADD OFFPAGE..5
(-6475 2500);
FORCEPROP 2 LAST $XR0 106 
J 0
(-6730 2500);
DISPLAY 0.638298 (-6730 2500);
PAINT MONO (-6730 2500);
FORCEPROP 2 LAST PATH I311
J 0
(-6750 2550);
DISPLAY 1.021277 (-6750 2550);
DISPLAY INVISIBLE (-6750 2550);
FORCEPROP 1 LAST COMMENT_BODY TRUE
J 0
(-6375 2425);
DISPLAY 0.872340 (-6375 2425);
PAINT GREEN (-6375 2425);
DISPLAY INVISIBLE (-6375 2425);
FORCEPROP 1 LAST OFFPAGE TRUE
J 0
(-6150 2375);
DISPLAY 0.872340 (-6150 2375);
PAINT GREEN (-6150 2375);
DISPLAY INVISIBLE (-6150 2375);
FORCEPROP 2 LAST CDS_LIB mstr_standard
J 0
(-6475 2500);
DISPLAY INVISIBLE (-6475 2500);
FORCEADD OFFPAGE..5
(-6475 2150);
FORCEPROP 2 LAST $XR0 106 
J 0
(-6730 2150);
DISPLAY 0.638298 (-6730 2150);
PAINT MONO (-6730 2150);
FORCEPROP 2 LAST PATH I312
J 0
(-6750 2200);
DISPLAY 1.021277 (-6750 2200);
DISPLAY INVISIBLE (-6750 2200);
FORCEPROP 1 LAST COMMENT_BODY TRUE
J 0
(-6375 2075);
DISPLAY 0.872340 (-6375 2075);
PAINT GREEN (-6375 2075);
DISPLAY INVISIBLE (-6375 2075);
FORCEPROP 1 LAST OFFPAGE TRUE
J 0
(-6150 2025);
DISPLAY 0.872340 (-6150 2025);
PAINT GREEN (-6150 2025);
DISPLAY INVISIBLE (-6150 2025);
FORCEPROP 2 LAST CDS_LIB standard
J 0
(-6475 2150);
DISPLAY INVISIBLE (-6475 2150);
FORCEADD OFFPAGE..1
(-6475 2250);
FORCEPROP 2 LAST $XR0 106 
J 0
(-6757 2250);
DISPLAY 0.638298 (-6757 2250);
PAINT MONO (-6757 2250);
FORCEPROP 2 LAST PATH I313
J 0
(-6725 2300);
DISPLAY 1.021277 (-6725 2300);
DISPLAY INVISIBLE (-6725 2300);
FORCEPROP 1 LAST COMMENT_BODY TRUE
J 0
(-6350 2150);
DISPLAY 0.872340 (-6350 2150);
PAINT GREEN (-6350 2150);
DISPLAY INVISIBLE (-6350 2150);
FORCEPROP 1 LAST OFFPAGE TRUE
J 0
(-6150 2125);
DISPLAY 0.872340 (-6150 2125);
PAINT GREEN (-6150 2125);
DISPLAY INVISIBLE (-6150 2125);
FORCEPROP 2 LAST CDS_LIB standard
J 0
(-6475 2250);
DISPLAY INVISIBLE (-6475 2250);
FORCEADD Q_RES..1
(-6550 2050);
FORCEPROP 1 LAST LOCATION R509
J 0
(-6875 2050);
DISPLAY 0.489362 (-6875 2050);
PAINT SKYBLUE (-6875 2050);
FORCEPROP 0 LAST $SEC 1
J 0
(-6725 2100);
DISPLAY 0.680851 (-6725 2100);
PAINT MONO (-6725 2100);
DISPLAY INVISIBLE (-6725 2100);
FORCEPROP 0 LAST CDS_SEC 1
J 0
(-6725 2100);
DISPLAY 1.021277 (-6725 2100);
DISPLAY INVISIBLE (-6725 2100);
FORCEPROP 1 LASTPIN (-6650 2050) $PN 1
J 0
(-6638 2062);
DISPLAY 0.489362 (-6638 2062);
PAINT MONO (-6638 2062);
FORCEPROP 1 LASTPIN (-6450 2050) $PN 2
J 0
(-6488 2062);
DISPLAY 0.489362 (-6488 2062);
PAINT MONO (-6488 2062);
FORCEPROP 1 LAST TOLERANCE 1%
J 0
(-6275 2050);
DISPLAY 0.489362 (-6275 2050);
PAINT SKYBLUE (-6275 2050);
FORCEPROP 1 LAST VALUE 15   
J 2
(-6225 2050);
DISPLAY 0.489362 (-6225 2050);
PAINT SKYBLUE (-6225 2050);
FORCEPROP 1 LAST PART_NUMBER CS01502FB11
J 0
(-6450 2025);
DISPLAY 0.489362 (-6450 2025);
PAINT SKYBLUE (-6450 2025);
FORCEPROP 1 LAST PACK_TYPE 0402LF
J 0
(-6875 2025);
DISPLAY 0.489362 (-6875 2025);
PAINT SKYBLUE (-6875 2025);
FORCEPROP 2 LAST CDS_LIB pure_quanta
J 0
(-6550 2050);
DISPLAY INVISIBLE (-6550 2050);
FORCEPROP 1 LAST PATH I314
J 0
(-6600 2200);
DISPLAY 0.978723 (-6600 2200);
PAINT WHITE (-6600 2200);
DISPLAY INVISIBLE (-6600 2200);
FORCEPROP 1 LAST WATTAGE 1/16W
J 2
(-6325 2175);
DISPLAY 0.638298 (-6325 2175);
PAINT SKYBLUE (-6325 2175);
DISPLAY INVISIBLE (-6325 2175);
FORCEPROP 1 LAST MATERIAL CHIP
J 0
(-6675 2175);
DISPLAY 0.638298 (-6675 2175);
PAINT SKYBLUE (-6675 2175);
DISPLAY INVISIBLE (-6675 2175);
FORCEADD OFFPAGE..5
(-6475 1950);
FORCEPROP 2 LAST $XR0 106 
J 0
(-6730 1950);
DISPLAY 0.638298 (-6730 1950);
PAINT MONO (-6730 1950);
FORCEPROP 2 LAST PATH I315
J 0
(-6750 2000);
DISPLAY 1.021277 (-6750 2000);
DISPLAY INVISIBLE (-6750 2000);
FORCEPROP 1 LAST COMMENT_BODY TRUE
J 0
(-6375 1875);
DISPLAY 0.872340 (-6375 1875);
PAINT GREEN (-6375 1875);
DISPLAY INVISIBLE (-6375 1875);
FORCEPROP 1 LAST OFFPAGE TRUE
J 0
(-6150 1825);
DISPLAY 0.872340 (-6150 1825);
PAINT GREEN (-6150 1825);
DISPLAY INVISIBLE (-6150 1825);
FORCEPROP 2 LAST CDS_LIB standard
J 0
(-6475 1950);
DISPLAY INVISIBLE (-6475 1950);
FORCEADD OFFPAGE..1
(-7425 2050);
FORCEPROP 2 LAST $XR0 106 
J 0
(-7677 2050);
DISPLAY 0.638298 (-7677 2050);
PAINT MONO (-7677 2050);
FORCEPROP 2 LAST PATH I316
J 0
(-7675 2100);
DISPLAY 1.021277 (-7675 2100);
DISPLAY INVISIBLE (-7675 2100);
FORCEPROP 1 LAST COMMENT_BODY TRUE
J 0
(-7300 1950);
DISPLAY 0.872340 (-7300 1950);
PAINT GREEN (-7300 1950);
DISPLAY INVISIBLE (-7300 1950);
FORCEPROP 1 LAST OFFPAGE TRUE
J 0
(-7100 1925);
DISPLAY 0.872340 (-7100 1925);
PAINT GREEN (-7100 1925);
DISPLAY INVISIBLE (-7100 1925);
FORCEPROP 2 LAST CDS_LIB mstr_standard
J 0
(-7425 2050);
DISPLAY INVISIBLE (-7425 2050);
FORCEADD CAD_NOTE..1
(-7600 2350);
FORCEPROP 0 LAST L1 R1983 PLACE CLOSE TO CPU < 25MM
J 0
(-7750 2225);
DISPLAY 0.617021 (-7750 2225);
PAINT WHITE (-7750 2225);
FORCEPROP 2 LAST CDS_LIB pure_quanta_power
J 0
(-7600 2350);
DISPLAY INVISIBLE (-7600 2350);
FORCEPROP 1 LAST COMMENT_BODY TRUE
J 0
(-7575 2450);
DISPLAY 0.574468 (-7575 2450);
PAINT WHITE (-7575 2450);
DISPLAY INVISIBLE (-7575 2450);
FORCEADD QUANTA_TITLE_BLOCK_C..1
(0 0);
FORCEPROP 0 LAST CDS_CON_LAST_MODIFIED Fri Mar 11 14:52:34 2022
J 0
(-1885 15);
DISPLAY INVISIBLE (-1885 15);
FORCEPROP 1 LAST CUSTOM_TXT_CDS <CON_LAST_MODIFIED>
J 0
(-1885 15);
DISPLAY 0.978723 (-1885 15);
FORCEPROP 2 LAST CUSTOM_TXT_CDS <XR_PAGE_TITLE>
J 0
(-7890 5250);
DISPLAY 0.638298 (-7890 5250);
PAINT PINK (-7890 5250);
DISPLAY INVISIBLE (-7890 5250);
FORCEPROP 1 LAST CUSTOM_TXT_CDS <NAME_2>
J 0
(-3175 50);
FORCEPROP 1 LAST CUSTOM_TXT_CDS <NAME_1>
J 0
(-3175 175);
FORCEPROP 1 LAST CUSTOM_TXT_CDS <Q_NUMBER>
J 0
(-1403 103);
DISPLAY 1.212766 (-1403 103);
FORCEPROP 1 LAST CUSTOM_TXT_CDS <Q_PROJ>
J 0
(-2382 102);
DISPLAY 1.212766 (-2382 102);
FORCEPROP 1 LAST CUSTOM_TXT_CDS <Q_REV>
J 0
(-184 103);
DISPLAY 1.212766 (-184 103);
FORCEPROP 1 LAST CUSTOM_TXT_CDS <CON_PAGE_NUM> OF <CON_TOTAL_PAGES>
J 0
(-446 18);
DISPLAY 0.978723 (-446 18);
FORCEPROP 1 LAST Q_TITLE CPU1 DDR CHJ
J 0
(-9366 26);
DISPLAY 2.446809 (-9366 26);
PAINT GREEN (-9366 26);
FORCEPROP 1 LAST Q_DEPT BU9
J 1
(-3763 49);
DISPLAY 1.957447 (-3763 49);
PAINT GREEN (-3763 49);
FORCEPROP 2 LAST PAGE_BORDER TRUE
J 0
(-7890 5250);
DISPLAY 0.638298 (-7890 5250);
PAINT PINK (-7890 5250);
DISPLAY INVISIBLE (-7890 5250);
FORCEPROP 1 LAST CDS_LMAN_SYM_OUTLINE -9475,6775,100,-125
J 0
(0 0);
DISPLAY 0.468085 (0 0);
PAINT GREEN (0 0);
DISPLAY INVISIBLE (0 0);
FORCEPROP 2 LAST CDS_LIB pure_quanta
J 0
(0 0);
DISPLAY INVISIBLE (0 0);
FORCEPROP 1 LAST COMMENT_BODY TRUE
J 0
(12 -13);
DISPLAY 0.978723 (12 -13);
PAINT GREEN (12 -13);
DISPLAY INVISIBLE (12 -13);
FORCEPROP 2 LAST CDS_XR_PAGE_TITLE CR-46 : @T6G_MB_LIB.T6G(SCH_1):PAGE46
J 0
(-7890 5250);
DISPLAY 0.638298 (-7890 5250);
PAINT PINK (-7890 5250);
DISPLAY INVISIBLE (-7890 5250);
WIRE 17 -1 (-3200 5225)(-3200 5175);
WIRE 17 -1 (-3200 5275)(-3200 5225);
WIRE 17 -1 (-3200 5175)(-3200 5125);
WIRE 17 -1 (-3200 5025)(-3200 5125);
WIRE 17 -1 (-3200 5325)(-3200 5275);
WIRE 17 -1 (-3200 5375)(-3200 5325);
WIRE 17 -1 (-3200 4975)(-3200 5025);
WIRE 17 -1 (-3200 4925)(-3200 4975);
WIRE 17 -1 (-3200 5425)(-3200 5375);
WIRE 17 -1 (-3200 5475)(-3200 5425);
WIRE 17 -1 (-3200 4875)(-3200 4925);
WIRE 17 -1 (-3200 4875)(-3200 4825);
WIRE 17 -1 (-3200 5575)(-3200 5475);
WIRE 17 -1 (-3200 5625)(-3200 5575);
WIRE 17 -1 (-3200 4825)(-3200 4775);
WIRE 17 -1 (-3200 4775)(-3200 4725);
WIRE 17 -1 (-3200 5675)(-3200 5625);
WIRE 17 -1 (-3200 5725)(-3200 5675);
WIRE 17 -1 (-3200 4725)(-3200 4675);
WIRE 17 -1 (-3200 4675)(-3200 4575);
WIRE 17 -1 (-3200 5775)(-3200 5725);
WIRE 17 -1 (-3200 5825)(-3200 5775);
WIRE 17 -1 (-3200 4575)(-3200 4525);
WIRE 17 -1 (-3200 4525)(-3200 4475);
WIRE 17 -1 (-3200 5875)(-3200 5825);
WIRE 17 -1 (-3200 5925)(-3200 5875);
WIRE 17 -1 (-3200 4475)(-3200 4425);
WIRE 17 -1 (-3200 4375)(-3200 4425);
WIRE 17 -1 (-3200 5925)(-2575 5925);
FORCEPROP 2 LAST SIG_NAME M_J_CPU1_SA_DQ<31:0>
J 2
(-2635 5935);
DISPLAY 0.489362 (-2635 5935);
WIRE 17 -1 (-3200 4225)(-3200 4275);
WIRE 17 -1 (-3200 4275)(-3200 4325);
WIRE 17 -1 (-3200 4325)(-3200 4375);
WIRE 17 -1 (-3200 4125)(-2575 4125);
FORCEPROP 2 LAST SIG_NAME M_J_CPU1_SB_DQ<31:0>
J 2
(-2635 4135);
DISPLAY 0.489362 (-2635 4135);
WIRE 17 -1 (-3200 3075)(-3200 3125);
WIRE 17 -1 (-3200 3075)(-3200 3025);
WIRE 17 -1 (-3200 3125)(-3200 3175);
WIRE 17 -1 (-3200 3175)(-3200 3225);
WIRE 17 -1 (-3200 3025)(-3200 2975);
WIRE 17 -1 (-3200 2975)(-3200 2925);
WIRE 17 -1 (-3200 3225)(-3200 3325);
WIRE 17 -1 (-3200 3375)(-3200 3325);
WIRE 17 -1 (-3200 2925)(-3200 2875);
WIRE 17 -1 (-3200 2875)(-3200 2775);
WIRE 17 -1 (-3200 3425)(-3200 3375);
WIRE 17 -1 (-3200 3475)(-3200 3425);
WIRE 17 -1 (-3200 2775)(-3200 2725);
WIRE 17 -1 (-3200 2725)(-3200 2675);
WIRE 17 -1 (-3200 3525)(-3200 3475);
WIRE 17 -1 (-3200 3575)(-3200 3525);
WIRE 17 -1 (-3200 2675)(-3200 2625);
WIRE 17 -1 (-3200 2575)(-3200 2625);
WIRE 17 -1 (-3200 3625)(-3200 3575);
WIRE 17 -1 (-3200 3675)(-3200 3625);
WIRE 17 -1 (-3200 2525)(-3200 2575);
WIRE 17 -1 (-3200 2475)(-3200 2525);
WIRE 17 -1 (-3200 3775)(-3200 3675);
WIRE 17 -1 (-3200 3825)(-3200 3775);
WIRE 17 -1 (-3200 2425)(-3200 2475);
WIRE 17 -1 (-3200 3875)(-3200 3825);
WIRE 17 -1 (-3200 3925)(-3200 3875);
WIRE 17 -1 (-3200 3975)(-3200 3925);
WIRE 17 -1 (-3200 4025)(-3200 3975);
WIRE 17 -1 (-3200 4075)(-3200 4025);
WIRE 17 -1 (-3200 4125)(-3200 4075);
WIRE 17 -1 (-3200 2075)(-3200 2125);
WIRE 17 -1 (-3200 2025)(-3200 2075);
WIRE 17 -1 (-3200 2125)(-3200 2175);
WIRE 17 -1 (-3200 2225)(-3200 2175);
WIRE 17 -1 (-3200 1975)(-3200 2025);
WIRE 17 -1 (-3200 2225)(-3200 2275);
WIRE 17 -1 (-3200 2325)(-3200 2275);
WIRE 17 -1 (-3200 2325)(-3200 2350);
WIRE 17 -1 (-3200 2350)(-2700 2350);
FORCEPROP 2 LAST SIG_NAME M_J_CPU1_SA_CB<7:0>
J 2
(-2700 2360);
DISPLAY 0.489362 (-2700 2360);
WIRE 17 -1 (-3200 1525)(-3200 1575);
WIRE 17 -1 (-3200 1575)(-3200 1625);
WIRE 17 -1 (-3200 1625)(-3200 1675);
WIRE 17 -1 (-3200 1675)(-3200 1725);
WIRE 17 -1 (-3200 1775)(-3200 1725);
WIRE 17 -1 (-3200 1775)(-3200 1825);
WIRE 17 -1 (-3200 1875)(-3200 1825);
WIRE 17 -1 (-3200 1875)(-3200 1900);
WIRE 17 -1 (-3200 1900)(-2700 1900);
FORCEPROP 2 LAST SIG_NAME M_J_CPU1_SB_CB<7:0>
J 2
(-2700 1910);
DISPLAY 0.489362 (-2700 1910);
WIRE 17 -1 (-5725 5725)(-5725 5625);
WIRE 17 -1 (-5725 5825)(-5725 5725);
WIRE 17 -1 (-5725 5625)(-5725 5525);
WIRE 17 -1 (-5725 5425)(-5725 5525);
WIRE 17 -1 (-5725 5925)(-5725 5825);
WIRE 17 -1 (-5725 5925)(-6525 5925);
FORCEPROP 2 LAST SIG_NAME M_J_CPU1_SA_DQS_DP<9:0>
J 2
(-5960 5935);
DISPLAY 0.489362 (-5960 5935);
WIRE 17 -1 (-5725 5225)(-5725 5125);
WIRE 17 -1 (-5725 5225)(-5725 5325);
WIRE 17 -1 (-5725 5125)(-5725 5025);
WIRE 17 -1 (-5725 5325)(-5725 5425);
WIRE 17 -1 (-5925 5275)(-5925 5375);
WIRE 17 -1 (-5925 5175)(-5925 5275);
WIRE 17 -1 (-5925 5375)(-5925 5475);
WIRE 17 -1 (-5925 5575)(-5925 5475);
WIRE 17 -1 (-5925 5175)(-5925 5075);
WIRE 17 -1 (-5925 5075)(-5925 4975);
WIRE 17 -1 (-5925 5675)(-5925 5575);
WIRE 17 -1 (-5925 5775)(-5925 5675);
WIRE 17 -1 (-5925 5875)(-5925 5775);
FORCEPROP 2 LAST SIG_NAME M_J_CPU1_SA_DQS_DN<9:0>
J 2
(-5960 5885);
DISPLAY 0.489362 (-5960 5885);
WIRE 17 -1 (-5725 4675)(-5725 4575);
WIRE 17 -1 (-5725 4775)(-5725 4675);
WIRE 17 -1 (-5725 4575)(-5725 4475);
WIRE 17 -1 (-5725 4375)(-5725 4475);
WIRE 17 -1 (-5725 4875)(-5725 4775);
WIRE 17 -1 (-5725 4875)(-6525 4875);
FORCEPROP 2 LAST SIG_NAME M_J_CPU1_SB_DQS_DP<9:0>
J 2
(-5960 4885);
DISPLAY 0.489362 (-5960 4885);
WIRE 17 -1 (-5725 4175)(-5725 4075);
WIRE 17 -1 (-5725 4175)(-5725 4275);
WIRE 17 -1 (-5725 4075)(-5725 3975);
WIRE 17 -1 (-5725 4275)(-5725 4375);
WIRE 17 -1 (-5925 4125)(-5925 4025);
WIRE 17 -1 (-5925 4125)(-5925 4225);
WIRE 17 -1 (-5925 4025)(-5925 3925);
WIRE 17 -1 (-5925 4225)(-5925 4325);
WIRE 17 -1 (-5925 4325)(-5925 4425);
WIRE 17 -1 (-5925 4525)(-5925 4425);
WIRE 17 -1 (-5925 4625)(-5925 4525);
WIRE 17 -1 (-5925 4725)(-5925 4625);
WIRE 17 -1 (-5925 4825)(-5925 4725);
FORCEPROP 2 LAST SIG_NAME M_J_CPU1_SB_DQS_DN<9:0>
J 2
(-5960 4835);
DISPLAY 0.489362 (-5960 4835);
WIRE 17 -1 (-5925 3125)(-5925 3175);
WIRE 17 -1 (-5925 3075)(-5925 3125);
WIRE 17 -1 (-5925 3175)(-5925 3225);
WIRE 17 -1 (-5925 3225)(-5925 3275);
WIRE 17 -1 (-5925 3275)(-5925 3325);
WIRE 17 -1 (-5925 3325)(-5925 3375);
WIRE 17 -1 (-5925 3375)(-6425 3375);
FORCEPROP 2 LAST SIG_NAME M_J_CPU1_SB_CA<6:0>
J 0
(-6425 3385);
DISPLAY 0.489362 (-6425 3385);
WIRE 17 -1 (-5925 3575)(-5925 3625);
WIRE 17 -1 (-5925 3525)(-5925 3575);
WIRE 17 -1 (-5925 3625)(-5925 3675);
WIRE 17 -1 (-5925 3675)(-5925 3725);
WIRE 17 -1 (-5925 3475)(-5925 3525);
WIRE 17 -1 (-5925 3725)(-5925 3775);
WIRE 17 -1 (-5925 3775)(-6425 3775);
FORCEPROP 2 LAST SIG_NAME M_J_CPU1_SA_CA<6:0>
J 0
(-6425 3785);
DISPLAY 0.489362 (-6425 3785);
WIRE 17 -1 (-5925 5875)(-6525 5875);
WIRE 17 -1 (-5925 4825)(-6525 4825);
WIRE 16 -1 (-7375 2050)(-6650 2050);
FORCEPROP 2 LAST SIG_NAME M_J_CPU1_ALERT_N
J 0
(-7335 2060);
DISPLAY 0.489362 (-7335 2060);
WIRE 16 -1 (-6425 1100)(-5325 1100);
FORCEPROP 2 LAST SIG_NAME TP_M_J_CPU1_SA_TEST39J
J 0
(-6410 1110);
DISPLAY 0.489362 (-6410 1110);
FORCEPROP 2 LASTPROP $XRERR UNIQUE?
J 0
(-6665 1100);
DISPLAY 0.638298 (-6665 1100);
PAINT MONO (-6665 1100);
DISPLAY INVISIBLE (-6665 1100);
WIRE 16 -1 (-6450 2050)(-5325 2050);
FORCEPROP 2 LAST SIG_NAME M_J_CPU1_ALERT_R_N
J 0
(-6160 2060);
DISPLAY 0.489362 (-6160 2060);
FORCEPROP 2 LASTPROP $XRERR UNIQUE?
J 0
(-6400 2060);
DISPLAY 0.638298 (-6400 2060);
PAINT MONO (-6400 2060);
DISPLAY INVISIBLE (-6400 2060);
WIRE 16 -1 (-6425 2900)(-5325 2900);
FORCEPROP 2 LAST SIG_NAME M_J_CPU1_CLK_DP<0>
J 0
(-6425 2910);
DISPLAY 0.489362 (-6425 2910);
WIRE 16 -1 (-6425 2850)(-5325 2850);
FORCEPROP 2 LAST SIG_NAME M_J_CPU1_CLK_DN<0>
J 0
(-6425 2860);
DISPLAY 0.489362 (-6425 2860);
WIRE 16 -1 (-6425 2750)(-5325 2750);
FORCEPROP 2 LAST SIG_NAME M_J_CPU1_SA_CS_N<0>
J 0
(-6425 2760);
DISPLAY 0.489362 (-6425 2760);
WIRE 16 -1 (-6425 2700)(-5325 2700);
FORCEPROP 2 LAST SIG_NAME M_J_CPU1_SA_CS_N<1>
J 0
(-6425 2710);
DISPLAY 0.489362 (-6425 2710);
WIRE 16 -1 (-6425 2600)(-5325 2600);
FORCEPROP 2 LAST SIG_NAME M_J_CPU1_SA_RSP<0>
J 0
(-6425 2610);
DISPLAY 0.489362 (-6425 2610);
WIRE 16 -1 (-6425 2400)(-5325 2400);
FORCEPROP 2 LAST SIG_NAME M_J_CPU1_SB_CS_N<0>
J 0
(-6425 2410);
DISPLAY 0.489362 (-6425 2410);
WIRE 16 -1 (-6425 2350)(-5325 2350);
FORCEPROP 2 LAST SIG_NAME M_J_CPU1_SB_CS_N<1>
J 0
(-6425 2360);
DISPLAY 0.489362 (-6425 2360);
WIRE 16 -1 (-6425 2500)(-5325 2500);
FORCEPROP 2 LAST SIG_NAME M_J_CPU1_SA_PAR
J 0
(-6425 2510);
DISPLAY 0.489362 (-6425 2510);
WIRE 16 -1 (-6425 2150)(-5325 2150);
FORCEPROP 2 LAST SIG_NAME M_J_CPU1_SB_PAR
J 0
(-6425 2160);
DISPLAY 0.489362 (-6425 2160);
WIRE 16 -1 (-6425 2250)(-5325 2250);
FORCEPROP 2 LAST SIG_NAME M_J_CPU1_SB_RSP<0>
J 0
(-6425 2260);
DISPLAY 0.489362 (-6425 2260);
WIRE 16 -1 (-6425 1950)(-5325 1950);
FORCEPROP 2 LAST SIG_NAME M_J_CPU1_RESET_N
J 0
(-6425 1960);
DISPLAY 0.489362 (-6425 1960);
WIRE 16 -1 (-5825 3050)(-5325 3050);
WIRE 16 -1 (-5825 3500)(-5325 3500);
WIRE 16 -1 (-5825 3450)(-5325 3450);
WIRE 16 -1 (-5825 3750)(-5325 3750);
WIRE 16 -1 (-5825 3700)(-5325 3700);
WIRE 16 -1 (-5825 3650)(-5325 3650);
WIRE 16 -1 (-5825 3600)(-5325 3600);
WIRE 16 -1 (-5825 3550)(-5325 3550);
WIRE 16 -1 (-5825 3350)(-5325 3350);
WIRE 16 -1 (-5825 3300)(-5325 3300);
WIRE 16 -1 (-5825 3250)(-5325 3250);
WIRE 16 -1 (-5825 3200)(-5325 3200);
WIRE 16 -1 (-5825 3150)(-5325 3150);
WIRE 16 -1 (-5825 3100)(-5325 3100);
WIRE 16 -1 (-5825 4000)(-5325 4000);
WIRE 16 -1 (-5825 3900)(-5325 3900);
WIRE 16 -1 (-5625 4050)(-5325 4050);
WIRE 16 -1 (-5625 3950)(-5325 3950);
WIRE 16 -1 (-5825 4400)(-5325 4400);
WIRE 16 -1 (-5825 4800)(-5325 4800);
WIRE 16 -1 (-5825 5050)(-5325 5050);
WIRE 16 -1 (-5825 4950)(-5325 4950);
WIRE 16 -1 (-5825 4700)(-5325 4700);
WIRE 16 -1 (-5825 4600)(-5325 4600);
WIRE 16 -1 (-5825 4500)(-5325 4500);
WIRE 16 -1 (-5825 4300)(-5325 4300);
WIRE 16 -1 (-5825 4200)(-5325 4200);
WIRE 16 -1 (-5825 4100)(-5325 4100);
WIRE 16 -1 (-5625 4350)(-5325 4350);
WIRE 16 -1 (-5625 4550)(-5325 4550);
WIRE 16 -1 (-5625 4450)(-5325 4450);
WIRE 16 -1 (-5625 4250)(-5325 4250);
WIRE 16 -1 (-5625 4150)(-5325 4150);
WIRE 16 -1 (-5625 5100)(-5325 5100);
WIRE 16 -1 (-5625 5000)(-5325 5000);
WIRE 16 -1 (-5625 4850)(-5325 4850);
WIRE 16 -1 (-5625 4750)(-5325 4750);
WIRE 16 -1 (-5625 4650)(-5325 4650);
WIRE 16 -1 (-5825 5450)(-5325 5450);
WIRE 16 -1 (-5825 5350)(-5325 5350);
WIRE 16 -1 (-5825 5150)(-5325 5150);
WIRE 16 -1 (-5825 5850)(-5325 5850);
WIRE 16 -1 (-5825 5750)(-5325 5750);
WIRE 16 -1 (-5825 5650)(-5325 5650);
WIRE 16 -1 (-5825 5550)(-5325 5550);
WIRE 16 -1 (-5825 5250)(-5325 5250);
WIRE 16 -1 (-5625 5500)(-5325 5500);
WIRE 16 -1 (-5625 5600)(-5325 5600);
WIRE 16 -1 (-5625 5400)(-5325 5400);
WIRE 16 -1 (-5625 5300)(-5325 5300);
WIRE 16 -1 (-5625 5200)(-5325 5200);
WIRE 16 -1 (-5625 5900)(-5325 5900);
WIRE 16 -1 (-5625 5800)(-5325 5800);
WIRE 16 -1 (-5625 5700)(-5325 5700);
WIRE 16 -1 (-3725 2000)(-3300 2000);
WIRE 16 -1 (-3725 1950)(-3300 1950);
WIRE 16 -1 (-3725 1850)(-3300 1850);
WIRE 16 -1 (-3725 1800)(-3300 1800);
WIRE 16 -1 (-3725 1750)(-3300 1750);
WIRE 16 -1 (-3725 1700)(-3300 1700);
WIRE 16 -1 (-3725 1650)(-3300 1650);
WIRE 16 -1 (-3725 1600)(-3300 1600);
WIRE 16 -1 (-3725 1550)(-3300 1550);
WIRE 16 -1 (-3725 1500)(-3300 1500);
WIRE 16 -1 (-3725 2300)(-3300 2300);
WIRE 16 -1 (-3725 2250)(-3300 2250);
WIRE 16 -1 (-3725 2200)(-3300 2200);
WIRE 16 -1 (-3725 2150)(-3300 2150);
WIRE 16 -1 (-3725 2100)(-3300 2100);
WIRE 16 -1 (-3725 2050)(-3300 2050);
WIRE 16 -1 (-3725 3050)(-3300 3050);
WIRE 16 -1 (-3725 3000)(-3300 3000);
WIRE 16 -1 (-3725 2950)(-3300 2950);
WIRE 16 -1 (-3725 2900)(-3300 2900);
WIRE 16 -1 (-3725 2850)(-3300 2850);
WIRE 16 -1 (-3725 2750)(-3300 2750);
WIRE 16 -1 (-3725 2700)(-3300 2700);
WIRE 16 -1 (-3725 2650)(-3300 2650);
WIRE 16 -1 (-3725 2600)(-3300 2600);
WIRE 16 -1 (-3725 2550)(-3300 2550);
WIRE 16 -1 (-3725 2500)(-3300 2500);
WIRE 16 -1 (-3725 2450)(-3300 2450);
WIRE 16 -1 (-3725 2400)(-3300 2400);
WIRE 16 -1 (-3725 3750)(-3300 3750);
WIRE 16 -1 (-3725 3800)(-3300 3800);
WIRE 16 -1 (-3725 3850)(-3300 3850);
WIRE 16 -1 (-3725 3950)(-3300 3950);
WIRE 16 -1 (-3725 3900)(-3300 3900);
WIRE 16 -1 (-3725 4050)(-3300 4050);
WIRE 16 -1 (-3725 4000)(-3300 4000);
WIRE 16 -1 (-3725 3650)(-3300 3650);
WIRE 16 -1 (-3725 3600)(-3300 3600);
WIRE 16 -1 (-3725 3550)(-3300 3550);
WIRE 16 -1 (-3725 3500)(-3300 3500);
WIRE 16 -1 (-3725 3450)(-3300 3450);
WIRE 16 -1 (-3725 3400)(-3300 3400);
WIRE 16 -1 (-3725 3350)(-3300 3350);
WIRE 16 -1 (-3725 3300)(-3300 3300);
WIRE 16 -1 (-3725 3200)(-3300 3200);
WIRE 16 -1 (-3725 3150)(-3300 3150);
WIRE 16 -1 (-3725 3100)(-3300 3100);
WIRE 16 -1 (-3725 4200)(-3300 4200);
WIRE 16 -1 (-3725 4100)(-3300 4100);
WIRE 16 -1 (-3725 4700)(-3300 4700);
WIRE 16 -1 (-3725 5100)(-3300 5100);
WIRE 16 -1 (-3300 5000)(-3725 5000);
WIRE 16 -1 (-3725 4950)(-3300 4950);
WIRE 16 -1 (-3725 4900)(-3300 4900);
WIRE 16 -1 (-3725 4850)(-3300 4850);
WIRE 16 -1 (-3725 4800)(-3300 4800);
WIRE 16 -1 (-3725 4750)(-3300 4750);
WIRE 16 -1 (-3725 4650)(-3300 4650);
WIRE 16 -1 (-3725 4550)(-3300 4550);
WIRE 16 -1 (-3725 4500)(-3300 4500);
WIRE 16 -1 (-3725 4450)(-3300 4450);
WIRE 16 -1 (-3725 4400)(-3300 4400);
WIRE 16 -1 (-3725 4350)(-3300 4350);
WIRE 16 -1 (-3725 4300)(-3300 4300);
WIRE 16 -1 (-3725 4250)(-3300 4250);
WIRE 16 -1 (-3725 5900)(-3300 5900);
WIRE 16 -1 (-3725 5850)(-3300 5850);
WIRE 16 -1 (-3725 5800)(-3300 5800);
WIRE 16 -1 (-3725 5750)(-3300 5750);
WIRE 16 -1 (-3725 5700)(-3300 5700);
WIRE 16 -1 (-3725 5650)(-3300 5650);
WIRE 16 -1 (-3725 5600)(-3300 5600);
WIRE 16 -1 (-3725 5550)(-3300 5550);
WIRE 16 -1 (-3725 5450)(-3300 5450);
WIRE 16 -1 (-3725 5400)(-3300 5400);
WIRE 16 -1 (-3725 5350)(-3300 5350);
WIRE 16 -1 (-3725 5300)(-3300 5300);
WIRE 16 -1 (-3725 5250)(-3300 5250);
WIRE 16 -1 (-3725 5200)(-3300 5200);
WIRE 16 -1 (-3725 5150)(-3300 5150);
QUIT
